G04 ================== begin FILE IDENTIFICATION RECORD ==================*
G04 Layout Name:  13948-1b.brd*
G04 Film Name:    L4VCC*
G04 File Format:  Gerber RS274X*
G04 File Origin:  Cadence Allegro 16.5-S045*
G04 Origin Date:  Thu Nov 13 15:46:13 2014*
G04 *
G04 Layer:  VIA CLASS/L4VCC*
G04 Layer:  PIN/L4VCC*
G04 Layer:  PACKAGE GEOMETRY/PWRVCC*
G04 Layer:  ETCH/L4VCC*
G04 Layer:  DRAWING FORMAT/LAYER_PCB_STORY*
G04 Layer:  DRAWING FORMAT/LAYER_L4VCC*
G04 *
G04 Offset:    (0.00 0.00)*
G04 Mirror:    No*
G04 Mode:      Negative*
G04 Rotation:  0*
G04 FullContactRelief:  No*
G04 UndefLineWidth:     6.00*
G04 ================== end FILE IDENTIFICATION RECORD ====================*
%FSLAX35Y35*MOIN*%
%IR0*IPPOS*OFA0.00000B0.00000*MIA0B0*SFA1.00000B1.00000*%
%ADD17C,.03*%
%ADD13C,.032*%
%ADD46C,.06*%
%ADD42C,.07*%
%ADD41C,.062*%
%ADD19C,.036*%
%ADD18C,.063*%
%ADD12C,.09*%
%ADD35C,.064*%
%ADD22C,.073*%
%ADD38C,.066*%
%ADD30C,.057*%
%ADD40C,.076*%
%ADD27C,.059*%
%ADD23C,.068*%
%ADD32C,.078*%
%ADD15C,.089*%
%AMMACRO43*
4,1,14,.02707,.01293,
.028904,.008033,
.02986,.002892,
.029908,-.002337,
.029048,-.007495,
.027305,-.012426,
.02707,-.01293,
.03079,-.01665,
.033213,-.01105,
.034628,-.005115,
.03499,.000976,
.034289,.007037,
.032546,.012884,
.03079,.01665,
.02707,.01293,
270.*
4,1,14,.01293,-.02707,
.008033,-.028904,
.002892,-.02986,
-.002337,-.029908,
-.007495,-.029048,
-.012426,-.027305,
-.01293,-.02707,
-.01665,-.03079,
-.01105,-.033213,
-.005115,-.034628,
.000976,-.03499,
.007037,-.034289,
.012884,-.032546,
.01665,-.03079,
.01293,-.02707,
270.*
4,1,14,-.02707,-.01293,
-.028904,-.008033,
-.02986,-.002892,
-.029908,.002337,
-.029048,.007495,
-.027305,.012426,
-.02707,.01293,
-.03079,.01665,
-.033213,.01105,
-.034628,.005115,
-.03499,-.000976,
-.034289,-.007037,
-.032546,-.012884,
-.03079,-.01665,
-.02707,-.01293,
270.*
4,1,14,-.01293,.02707,
-.008033,.028904,
-.002892,.02986,
.002337,.029908,
.007495,.029048,
.012426,.027305,
.01293,.02707,
.01665,.03079,
.01105,.033213,
.005115,.034628,
-.000976,.03499,
-.007037,.034289,
-.012884,.032546,
-.01665,.03079,
-.01293,.02707,
270.*
%
%ADD43MACRO43*%
%AMMACRO28*
4,1,15,.00398,.00044,
.003999,.000208,
.004004,-.000025,
.003996,-.000258,
.00398,-.00044,
.00483,-.00129,
.004897,-.001007,
.004947,-.000721,
.004981,-.000432,
.004997,-.000141,
.004997,.000149,
.00498,.00044,
.004946,.000729,
.004895,.001015,
.00483,.00129,
.00398,.00044,
90.*
4,1,15,.00044,-.00398,
.000208,-.003999,
-.000025,-.004004,
-.000258,-.003996,
-.00044,-.00398,
-.00129,-.00483,
-.001007,-.004897,
-.000721,-.004947,
-.000432,-.004981,
-.000141,-.004997,
.000149,-.004997,
.00044,-.00498,
.000729,-.004946,
.001015,-.004895,
.00129,-.00483,
.00044,-.00398,
90.*
4,1,15,-.00398,-.00044,
-.003999,-.000208,
-.004004,.000025,
-.003996,.000258,
-.00398,.00044,
-.00483,.00129,
-.004897,.001007,
-.004947,.000721,
-.004981,.000432,
-.004997,.000141,
-.004997,-.000149,
-.00498,-.00044,
-.004946,-.000729,
-.004895,-.001015,
-.00483,-.00129,
-.00398,-.00044,
90.*
4,1,15,-.00044,.00398,
-.000208,.003999,
.000025,.004004,
.000258,.003996,
.00044,.00398,
.00129,.00483,
.001007,.004897,
.000721,.004947,
.000432,.004981,
.000141,.004997,
-.000149,.004997,
-.00044,.00498,
-.000729,.004946,
-.001015,.004895,
-.00129,.00483,
-.00044,.00398,
90.*
%
%ADD28MACRO28*%
%AMMACRO10*
4,1,15,.00398,.00044,
.003999,.000208,
.004004,-.000025,
.003996,-.000258,
.00398,-.00044,
.00483,-.00129,
.004897,-.001007,
.004947,-.000721,
.004981,-.000432,
.004997,-.000141,
.004997,.000149,
.00498,.00044,
.004946,.000729,
.004895,.001015,
.00483,.00129,
.00398,.00044,
0.0*
4,1,15,.00044,-.00398,
.000208,-.003999,
-.000025,-.004004,
-.000258,-.003996,
-.00044,-.00398,
-.00129,-.00483,
-.001007,-.004897,
-.000721,-.004947,
-.000432,-.004981,
-.000141,-.004997,
.000149,-.004997,
.00044,-.00498,
.000729,-.004946,
.001015,-.004895,
.00129,-.00483,
.00044,-.00398,
0.0*
4,1,15,-.00398,-.00044,
-.003999,-.000208,
-.004004,.000025,
-.003996,.000258,
-.00398,.00044,
-.00483,.00129,
-.004897,.001007,
-.004947,.000721,
-.004981,.000432,
-.004997,.000141,
-.004997,-.000149,
-.00498,-.00044,
-.004946,-.000729,
-.004895,-.001015,
-.00483,-.00129,
-.00398,-.00044,
0.0*
4,1,15,-.00044,.00398,
-.000208,.003999,
.000025,.004004,
.000258,.003996,
.00044,.00398,
.00129,.00483,
.001007,.004897,
.000721,.004947,
.000432,.004981,
.000141,.004997,
-.000149,.004997,
-.00044,.00498,
-.000729,.004946,
-.001015,.004895,
-.00129,.00483,
-.00044,.00398,
0.0*
%
%ADD10MACRO10*%
%AMMACRO44*
4,1,13,.02442,.01028,
.025834,.005883,
.026463,.001308,
.026288,-.003307,
.025315,-.007822,
.02442,-.01028,
.02819,-.01405,
.030201,-.008941,
.031295,-.003561,
.031438,.001927,
.030626,.007357,
.028883,.012564,
.02819,.01405,
.02442,.01028,
180.*
4,1,13,.01028,-.02442,
.005883,-.025834,
.001308,-.026463,
-.003307,-.026288,
-.007822,-.025315,
-.01028,-.02442,
-.01405,-.02819,
-.008941,-.030201,
-.003561,-.031295,
.001927,-.031438,
.007357,-.030626,
.012564,-.028883,
.01405,-.02819,
.01028,-.02442,
180.*
4,1,13,-.02442,-.01028,
-.025834,-.005883,
-.026463,-.001308,
-.026288,.003307,
-.025315,.007822,
-.02442,.01028,
-.02819,.01405,
-.030201,.008941,
-.031295,.003561,
-.031438,-.001927,
-.030626,-.007357,
-.028883,-.012564,
-.02819,-.01405,
-.02442,-.01028,
180.*
4,1,13,-.01028,.02442,
-.005883,.025834,
-.001308,.026463,
.003307,.026288,
.007822,.025315,
.01028,.02442,
.01405,.02819,
.008941,.030201,
.003561,.031295,
-.001927,.031438,
-.007357,.030626,
-.012564,.028883,
-.01405,.02819,
-.01028,.02442,
180.*
%
%ADD44MACRO44*%
%AMMACRO31*
4,1,19,.02211,.00797,
.022536,.006671,
.022886,.005349,
.023158,.00401,
.023352,.002656,
.023467,.001294,
.023503,-.000073,
.023459,-.001439,
.023335,-.002801,
.023133,-.004153,
.022852,-.005491,
.022494,-.00681,
.02211,-.00797,
.02594,-.0118,
.027595,-.007116,
.028411,-.002216,
.028365,.002751,
.027456,.007635,
.02594,.0118,
.02211,.00797,
180.*
4,1,19,.00797,-.02211,
.006671,-.022536,
.005349,-.022886,
.00401,-.023158,
.002656,-.023352,
.001294,-.023467,
-.000073,-.023503,
-.001439,-.023459,
-.002801,-.023335,
-.004153,-.023133,
-.005491,-.022852,
-.00681,-.022494,
-.00797,-.02211,
-.0118,-.02594,
-.007116,-.027595,
-.002216,-.028411,
.002751,-.028365,
.007635,-.027456,
.0118,-.02594,
.00797,-.02211,
180.*
4,1,19,-.02211,-.00797,
-.022536,-.006671,
-.022886,-.005349,
-.023158,-.00401,
-.023352,-.002656,
-.023467,-.001294,
-.023503,.000073,
-.023459,.001439,
-.023335,.002801,
-.023133,.004153,
-.022852,.005491,
-.022494,.00681,
-.02211,.00797,
-.02594,.0118,
-.027595,.007116,
-.028411,.002216,
-.028365,-.002751,
-.027456,-.007635,
-.02594,-.0118,
-.02211,-.00797,
180.*
4,1,19,-.00797,.02211,
-.006671,.022536,
-.005349,.022886,
-.00401,.023158,
-.002656,.023352,
-.001294,.023467,
.000073,.023503,
.001439,.023459,
.002801,.023335,
.004153,.023133,
.005491,.022852,
.00681,.022494,
.00797,.02211,
.0118,.02594,
.007116,.027595,
.002216,.028411,
-.002751,.028365,
-.007635,.027456,
-.0118,.02594,
-.00797,.02211,
180.*
%
%ADD31MACRO31*%
%AMMACRO45*
4,1,13,.02632,.01218,
.028035,.007425,
.028899,.002443,
.028884,-.002612,
.027991,-.007588,
.02632,-.01218,
.03005,-.01591,
.032356,-.01045,
.033679,-.004673,
.033979,.001247,
.033246,.007128,
.031504,.012793,
.03005,.01591,
.02632,.01218,
180.*
4,1,13,.01218,-.02632,
.007425,-.028035,
.002443,-.028899,
-.002612,-.028884,
-.007588,-.027991,
-.01218,-.02632,
-.01591,-.03005,
-.01045,-.032356,
-.004673,-.033679,
.001247,-.033979,
.007128,-.033246,
.012793,-.031504,
.01591,-.03005,
.01218,-.02632,
180.*
4,1,13,-.02632,-.01218,
-.028035,-.007425,
-.028899,-.002443,
-.028884,.002612,
-.027991,.007588,
-.02632,.01218,
-.03005,.01591,
-.032356,.01045,
-.033679,.004673,
-.033979,-.001247,
-.033246,-.007128,
-.031504,-.012793,
-.03005,-.01591,
-.02632,-.01218,
180.*
4,1,13,-.01218,.02632,
-.007425,.028035,
-.002443,.028899,
.002612,.028884,
.007588,.027991,
.01218,.02632,
.01591,.03005,
.01045,.032356,
.004673,.033679,
-.001247,.033979,
-.007128,.033246,
-.012793,.031504,
-.01591,.03005,
-.01218,.02632,
180.*
%
%ADD45MACRO45*%
%ADD36O,.217X.154*%
%ADD29C,.121*%
%ADD14C,.114*%
%ADD25C,.154*%
%ADD37C,.119*%
%ADD34C,.156*%
%ADD26C,.166*%
%AMMACRO20*
4,1,15,.00398,.00044,
.003999,.000208,
.004004,-.000025,
.003996,-.000258,
.00398,-.00044,
.00483,-.00129,
.004897,-.001007,
.004947,-.000721,
.004981,-.000432,
.004997,-.000141,
.004997,.000149,
.00498,.00044,
.004946,.000729,
.004895,.001015,
.00483,.00129,
.00398,.00044,
180.*
4,1,15,.00044,-.00398,
.000208,-.003999,
-.000025,-.004004,
-.000258,-.003996,
-.00044,-.00398,
-.00129,-.00483,
-.001007,-.004897,
-.000721,-.004947,
-.000432,-.004981,
-.000141,-.004997,
.000149,-.004997,
.00044,-.00498,
.000729,-.004946,
.001015,-.004895,
.00129,-.00483,
.00044,-.00398,
180.*
4,1,15,-.00398,-.00044,
-.003999,-.000208,
-.004004,.000025,
-.003996,.000258,
-.00398,.00044,
-.00483,.00129,
-.004897,.001007,
-.004947,.000721,
-.004981,.000432,
-.004997,.000141,
-.004997,-.000149,
-.00498,-.00044,
-.004946,-.000729,
-.004895,-.001015,
-.00483,-.00129,
-.00398,-.00044,
180.*
4,1,15,-.00044,.00398,
-.000208,.003999,
.000025,.004004,
.000258,.003996,
.00044,.00398,
.00129,.00483,
.001007,.004897,
.000721,.004947,
.000432,.004981,
.000141,.004997,
-.000149,.004997,
-.00044,.00498,
-.000729,.004946,
-.001015,.004895,
-.00129,.00483,
-.00044,.00398,
180.*
%
%ADD20MACRO20*%
%AMMACRO16*
4,1,15,.00398,.00044,
.003999,.000208,
.004004,-.000025,
.003996,-.000258,
.00398,-.00044,
.00483,-.00129,
.004897,-.001007,
.004947,-.000721,
.004981,-.000432,
.004997,-.000141,
.004997,.000149,
.00498,.00044,
.004946,.000729,
.004895,.001015,
.00483,.00129,
.00398,.00044,
270.*
4,1,15,.00044,-.00398,
.000208,-.003999,
-.000025,-.004004,
-.000258,-.003996,
-.00044,-.00398,
-.00129,-.00483,
-.001007,-.004897,
-.000721,-.004947,
-.000432,-.004981,
-.000141,-.004997,
.000149,-.004997,
.00044,-.00498,
.000729,-.004946,
.001015,-.004895,
.00129,-.00483,
.00044,-.00398,
270.*
4,1,15,-.00398,-.00044,
-.003999,-.000208,
-.004004,.000025,
-.003996,.000258,
-.00398,.00044,
-.00483,.00129,
-.004897,.001007,
-.004947,.000721,
-.004981,.000432,
-.004997,.000141,
-.004997,-.000149,
-.00498,-.00044,
-.004946,-.000729,
-.004895,-.001015,
-.00483,-.00129,
-.00398,-.00044,
270.*
4,1,15,-.00044,.00398,
-.000208,.003999,
.000025,.004004,
.000258,.003996,
.00044,.00398,
.00129,.00483,
.001007,.004897,
.000721,.004947,
.000432,.004981,
.000141,.004997,
-.000149,.004997,
-.00044,.00498,
-.000729,.004946,
-.001015,.004895,
-.00129,.00483,
-.00044,.00398,
270.*
%
%ADD16MACRO16*%
%AMMACRO21*
4,1,13,.02327,.00913,
.024502,.004951,
.024989,.000621,
.024717,-.003728,
.023695,-.007964,
.02327,-.00913,
.02707,-.01293,
.028904,-.008033,
.02986,-.002892,
.029908,.002337,
.029048,.007495,
.027305,.012426,
.02707,.01293,
.02327,.00913,
0.0*
4,1,13,.00913,-.02327,
.004951,-.024502,
.000621,-.024989,
-.003728,-.024717,
-.007964,-.023695,
-.00913,-.02327,
-.01293,-.02707,
-.008033,-.028904,
-.002892,-.02986,
.002337,-.029908,
.007495,-.029048,
.012426,-.027305,
.01293,-.02707,
.00913,-.02327,
0.0*
4,1,13,-.02327,-.00913,
-.024502,-.004951,
-.024989,-.000621,
-.024717,.003728,
-.023695,.007964,
-.02327,.00913,
-.02707,.01293,
-.028904,.008033,
-.02986,.002892,
-.029908,-.002337,
-.029048,-.007495,
-.027305,-.012426,
-.02707,-.01293,
-.02327,-.00913,
0.0*
4,1,13,-.00913,.02327,
-.004951,.024502,
-.000621,.024989,
.003728,.024717,
.007964,.023695,
.00913,.02327,
.01293,.02707,
.008033,.028904,
.002892,.02986,
-.002337,.029908,
-.007495,.029048,
-.012426,.027305,
-.01293,.02707,
-.00913,.02327,
0.0*
%
%ADD21MACRO21*%
%AMMACRO33*
4,1,13,.03683,.01561,
.038981,.008977,
.039948,.002072,
.039701,-.004896,
.038247,-.011716,
.03683,-.01561,
.04061,-.01939,
.04336,-.012044,
.044793,-.004331,
.044864,.003513,
.043573,.01125,
.040957,.018645,
.04061,.01939,
.03683,.01561,
0.0*
4,1,13,.01561,-.03683,
.008977,-.038981,
.002072,-.039948,
-.004896,-.039701,
-.011716,-.038247,
-.01561,-.03683,
-.01939,-.04061,
-.012044,-.04336,
-.004331,-.044793,
.003513,-.044864,
.01125,-.043573,
.018645,-.040957,
.01939,-.04061,
.01561,-.03683,
0.0*
4,1,13,-.03683,-.01561,
-.038981,-.008977,
-.039948,-.002072,
-.039701,.004896,
-.038247,.011716,
-.03683,.01561,
-.04061,.01939,
-.04336,.012044,
-.044793,.004331,
-.044864,-.003513,
-.043573,-.01125,
-.040957,-.018645,
-.04061,-.01939,
-.03683,-.01561,
0.0*
4,1,13,-.01561,.03683,
-.008977,.038981,
-.002072,.039948,
.004896,.039701,
.011716,.038247,
.01561,.03683,
.01939,.04061,
.012044,.04336,
.004331,.044793,
-.003513,.044864,
-.01125,.043573,
-.018645,.040957,
-.01939,.04061,
-.01561,.03683,
0.0*
%
%ADD33MACRO33*%
%AMMACRO24*
4,1,14,.02819,.01405,
.030201,.008941,
.031295,.003561,
.031438,-.001927,
.030626,-.007357,
.028883,-.012564,
.02819,-.01405,
.03189,-.01775,
.034488,-.011943,
.036038,-.005773,
.036493,.000573,
.035839,.006901,
.034096,.01302,
.03189,.01775,
.02819,.01405,
0.0*
4,1,14,.01405,-.02819,
.008941,-.030201,
.003561,-.031295,
-.001927,-.031438,
-.007357,-.030626,
-.012564,-.028883,
-.01405,-.02819,
-.01775,-.03189,
-.011943,-.034488,
-.005773,-.036038,
.000573,-.036493,
.006901,-.035839,
.01302,-.034096,
.01775,-.03189,
.01405,-.02819,
0.0*
4,1,14,-.02819,-.01405,
-.030201,-.008941,
-.031295,-.003561,
-.031438,.001927,
-.030626,.007357,
-.028883,.012564,
-.02819,.01405,
-.03189,.01775,
-.034488,.011943,
-.036038,.005773,
-.036493,-.000573,
-.035839,-.006901,
-.034096,-.01302,
-.03189,-.01775,
-.02819,-.01405,
0.0*
4,1,14,-.01405,.02819,
-.008941,.030201,
-.003561,.031295,
.001927,.031438,
.007357,.030626,
.012564,.028883,
.01405,.02819,
.01775,.03189,
.011943,.034488,
.005773,.036038,
-.000573,.036493,
-.006901,.035839,
-.01302,.034096,
-.01775,.03189,
-.01405,.02819,
0.0*
%
%ADD24MACRO24*%
%AMMACRO11*
4,1,14,.0575,.02922,
.0617,.018791,
.064026,.007792,
.064406,-.003445,
.06283,-.014576,
.059344,-.025265,
.0575,-.02922,
.06121,-.03292,
.065997,-.021791,
.068778,-.01,
.069469,.002095,
.06805,.014127,
.064563,.025729,
.06121,.03292,
.0575,.02922,
90.*
4,1,14,.02922,-.0575,
.018791,-.0617,
.007792,-.064026,
-.003445,-.064406,
-.014576,-.06283,
-.025265,-.059344,
-.02922,-.0575,
-.03292,-.06121,
-.021791,-.065997,
-.01,-.068778,
.002095,-.069469,
.014127,-.06805,
.025729,-.064563,
.03292,-.06121,
.02922,-.0575,
90.*
4,1,14,-.0575,-.02922,
-.0617,-.018791,
-.064026,-.007792,
-.064406,.003445,
-.06283,.014576,
-.059344,.025265,
-.0575,.02922,
-.06121,.03292,
-.065997,.021791,
-.068778,.01,
-.069469,-.002095,
-.06805,-.014127,
-.064563,-.025729,
-.06121,-.03292,
-.0575,-.02922,
90.*
4,1,14,-.02922,.0575,
-.018791,.0617,
-.007792,.064026,
.003445,.064406,
.014576,.06283,
.025265,.059344,
.02922,.0575,
.03292,.06121,
.021791,.065997,
.01,.068778,
-.002095,.069469,
-.014127,.06805,
-.025729,.064563,
-.03292,.06121,
-.02922,.0575,
90.*
%
%ADD11MACRO11*%
%AMMACRO39*
4,1,13,.02556,.01142,
.027155,.006808,
.027924,.001989,
.027846,-.00289,
.026921,-.007681,
.02556,-.01142,
.02931,-.01517,
.031499,-.00985,
.032731,-.004231,
.032968,.001517,
.032204,.007219,
.030461,.012702,
.02931,.01517,
.02556,.01142,
0.0*
4,1,13,.01142,-.02556,
.006808,-.027155,
.001989,-.027924,
-.00289,-.027846,
-.007681,-.026921,
-.01142,-.02556,
-.01517,-.02931,
-.00985,-.031499,
-.004231,-.032731,
.001517,-.032968,
.007219,-.032204,
.012702,-.030461,
.01517,-.02931,
.01142,-.02556,
0.0*
4,1,13,-.02556,-.01142,
-.027155,-.006808,
-.027924,-.001989,
-.027846,.00289,
-.026921,.007681,
-.02556,.01142,
-.02931,.01517,
-.031499,.00985,
-.032731,.004231,
-.032968,-.001517,
-.032204,-.007219,
-.030461,-.012702,
-.02931,-.01517,
-.02556,-.01142,
0.0*
4,1,13,-.01142,.02556,
-.006808,.027155,
-.001989,.027924,
.00289,.027846,
.007681,.026921,
.01142,.02556,
.01517,.02931,
.00985,.031499,
.004231,.032731,
-.001517,.032968,
-.007219,.032204,
-.012702,.030461,
-.01517,.02931,
-.01142,.02556,
0.0*
%
%ADD39MACRO39*%
%ADD47C,.02*%
%ADD48C,.006*%
%ADD60C,.06204*%
%ADD58C,.07204*%
%ADD57C,.06404*%
%ADD61C,.05604*%
%ADD59C,.05804*%
%ADD52C,.08504*%
%ADD51C,.08604*%
%ADD49O,.21302X.15002*%
%ADD50O,.21304X.15004*%
%ADD56C,.15004*%
%ADD55C,.15204*%
%ADD54C,.11704*%
%ADD53C,.16204*%
G75*
%LPD*%
G75*
G36*
G01X-6000Y-6000D02*
X1406000D01*
Y1029622D01*
X-6000D01*
Y-6000D01*
G37*
%LPC*%
G75*
G36*
G01X1209638Y171261D02*
G03X1209634Y171487I-6941J-10D01*
G01Y172503D01*
X1209500Y172637D01*
X1209488Y172695D01*
G03X1202697Y178201I-6791J-1435D01*
G02X1201764Y179134I0J933D01*
G01Y210631D01*
G03X1201760Y210857I-6941J-10D01*
G01Y211873D01*
X1201626Y212007D01*
X1201614Y212065D01*
G03X1196258Y217421I-6791J-1435D01*
G01X1196200Y217433D01*
X1196066Y217567D01*
X1195050D01*
G03X1194824Y217571I-236J-6937D01*
G01X1116082D01*
G03X1115856Y217567I10J-6941D01*
G01X1114840D01*
X1114707Y217433D01*
X1114649Y217421D01*
G03X1109292Y212064I1434J-6791D01*
G01X1109280Y212006D01*
X1109146Y211873D01*
Y210857D01*
G03X1109142Y210631I6937J-236D01*
G01Y3937D01*
G02X1108209Y3004I-933J0D01*
G01X297047D01*
G02X296114Y3937I0J933D01*
G01Y7053D01*
X296811Y7750D01*
X411706D01*
X411736Y7586D01*
G03X416264I2264J414D01*
G01X416294Y7750D01*
X436567D01*
G03X440433I1933J1250D01*
G01X451311D01*
X475750Y32189D01*
Y164811D01*
X464725Y175836D01*
X464781Y175962D01*
G03X461741Y179002I-2102J938D01*
G01X461615Y178946D01*
X451520Y189041D01*
X451574Y189166D01*
G03X449598Y191142I-1378J598D01*
G01X449473Y191088D01*
X445221Y195340D01*
X445275Y195465D01*
G03X443299Y197441I-1378J598D01*
G01X443174Y197387D01*
X440311Y200250D01*
X438684D01*
G03X436512I-1086J-1038D01*
G01X435535D01*
G03X433363I-1086J-1038D01*
G01X429234D01*
G03X427064I-1085J-1039D01*
G01X426084D01*
G03X423914I-1085J-1039D01*
G01X397738D01*
G03X395568I-1085J-1039D01*
G01X386189D01*
X383300Y197361D01*
X383279Y197348D01*
G03X383250Y194794I776J-1286D01*
G01Y194180D01*
G03Y191644I805J-1268D01*
G01Y191027D01*
G03X382765Y188946I786J-1280D01*
G01X382850Y188811D01*
X381289Y187250D01*
X366543D01*
G03X363831I-1356J-645D01*
G01X354189D01*
X338250Y171311D01*
Y129311D01*
X337942Y129003D01*
X337869Y128996D01*
G03X336551Y127897I131J-1496D01*
G01X336511Y127750D01*
X336107D01*
G02X335806Y128413I0J400D01*
G03X336131Y129940I-1206J1055D01*
G01X336122Y129969D01*
X336112Y130000D01*
Y132499D01*
X336117Y132515D01*
X336118Y132517D01*
X336123Y132533D01*
G03X333069Y132559I-1523J498D01*
G01X333078Y132530D01*
X333088Y132499D01*
Y130000D01*
X333083Y129984D01*
X333082Y129982D01*
X333077Y129966D01*
G03X333394Y128413I1523J-498D01*
G02X333093Y127750I-301J-263D01*
G01X328238D01*
X328219Y127930D01*
G03X323639I-2290J-230D01*
G01X323620Y127750D01*
X320711D01*
X320611Y127850D01*
X319989D01*
X319889Y127750D01*
X312811D01*
X299195Y141366D01*
G02X299530Y142046I282J283D01*
G03X301567Y142816I301J2282D01*
G01X303145D01*
X303176Y142806D01*
G03Y145850I501J1522D01*
G01X303145Y145840D01*
X301567D01*
G03X297549Y144027I-1736J-1512D01*
G02X296869Y143692I-397J-53D01*
G01X295750Y144811D01*
Y340592D01*
G03Y343408I-1821J1408D01*
G01Y370311D01*
X234787Y431274D01*
X234777Y431340D01*
G03X232840Y433277I-2277J-340D01*
G01X232774Y433287D01*
X223250Y442811D01*
Y553689D01*
X248311Y578750D01*
X485189D01*
X506250Y557689D01*
Y519189D01*
X510689Y514750D01*
X540811D01*
X543761Y517700D01*
X543831D01*
X544300Y518169D01*
Y597331D01*
X539831Y601800D01*
X539169D01*
X539119Y601750D01*
X387311D01*
X385311Y603750D01*
X385250D01*
Y656119D01*
X385300Y656169D01*
Y656831D01*
X380831Y661300D01*
X375669D01*
X375619Y661250D01*
X229689D01*
X157221Y588782D01*
X157126Y588791D01*
G03X154609Y586274I-226J-2291D01*
G01X154618Y586179D01*
X149250Y580811D01*
Y400689D01*
X230750Y319189D01*
Y231390D01*
X116142D01*
G02X111272Y236260I0J4870D01*
G01Y299252D01*
G03X111268Y299538I-10878J-9D01*
G01Y300495D01*
X111193Y300570D01*
X111184Y300638D01*
G03X101780Y310042I-10790J-1386D01*
G01X101712Y310051D01*
X101637Y310126D01*
X100680D01*
G03X100394Y310130I-295J-10874D01*
G01X11811D01*
G02X3004Y318937I0J8807D01*
G01Y968504D01*
G02X19685Y985185I16681J0D01*
G01X103741D01*
G03X103967Y985189I-10J6941D01*
G01X104983D01*
X105116Y985323D01*
X105174Y985335D01*
G03X110531Y990692I-1434J6791D01*
G01X110543Y990750D01*
X110677Y990883D01*
Y991899D01*
G03X110681Y992125I-6937J236D01*
G01Y1015106D01*
X133020D01*
Y994291D01*
G03X133024Y994068I6744J9D01*
G01Y993048D01*
X133162Y992910D01*
X133175Y992852D01*
Y992851D01*
G03X146353I6589J1440D01*
G01Y992852D01*
X146366Y992910D01*
X146504Y993048D01*
Y994068D01*
G03X146508Y994291I-6740J232D01*
G01Y1015106D01*
X184594D01*
Y992126D01*
G03X184598Y991900I6941J10D01*
G01Y990883D01*
X184732Y990749D01*
X184744Y990691D01*
G03X190100Y985335I6791J1435D01*
G01X190158Y985323D01*
X190292Y985189D01*
X191309D01*
G03X191535Y985185I236J6937D01*
G01X261221D01*
G03X261447Y985189I-10J6941D01*
G01X262463D01*
X262596Y985323D01*
X262654Y985335D01*
G03X268011Y990692I-1434J6791D01*
G01X268023Y990750D01*
X268157Y990883D01*
Y991899D01*
G03X268161Y992125I-6937J236D01*
G01Y1015106D01*
X542468D01*
Y994291D01*
G03X542472Y994068I6744J9D01*
G01Y993048D01*
X542610Y992910D01*
X542623Y992852D01*
Y992851D01*
G03X555802I6590J1440D01*
G01Y992852D01*
X555815Y992910D01*
X555953Y993048D01*
Y994068D01*
G03X555957Y994291I-6740J232D01*
G01Y1015106D01*
X594043D01*
Y992125D01*
G03X594047Y991899I6941J10D01*
G01Y990883D01*
X594181Y990749D01*
X594193Y990691D01*
G03X599549Y985335I6791J1435D01*
G01X599607Y985323D01*
X599741Y985189D01*
X600757D01*
G03X600983Y985185I236J6937D01*
G01X713190D01*
G03X713416Y985189I-10J6941D01*
G01X714432D01*
X714566Y985323D01*
X714624Y985335D01*
G03X719980Y990691I-1435J6791D01*
G01X719992Y990749D01*
X720126Y990883D01*
Y991899D01*
G03X720130Y992125I-6937J236D01*
G01Y1015106D01*
X742468D01*
Y994291D01*
G03X742472Y994068I6744J9D01*
G01Y993048D01*
X742610Y992910D01*
X742623Y992852D01*
Y992851D01*
G03X755802I6590J1440D01*
G01Y992852D01*
X755815Y992910D01*
X755953Y993048D01*
Y994068D01*
G03X755957Y994291I-6740J232D01*
G01Y1015106D01*
X794043D01*
Y992125D01*
G03X794047Y991899I6941J10D01*
G01Y990883D01*
X794181Y990749D01*
X794193Y990691D01*
G03X799549Y985335I6791J1435D01*
G01X799607Y985323D01*
X799741Y985189D01*
X800757D01*
G03X800983Y985185I236J6937D01*
G01X902165D01*
G02X918846Y968504I0J-16681D01*
G01Y775590D01*
G03X918850Y775364I6941J10D01*
G01Y774348D01*
X918984Y774215D01*
X918996Y774157D01*
G03X924353Y768800I6791J1434D01*
G01X924411Y768788D01*
X924544Y768654D01*
X925560D01*
G03X925786Y768650I236J6937D01*
G01X984844D01*
G03X985070Y768654I-10J6941D01*
G01X986086D01*
X986220Y768788D01*
X986278Y768800D01*
G03X991634Y774156I-1435J6791D01*
G01X991646Y774214D01*
X991780Y774348D01*
Y775364D01*
G03X991784Y775590I-6937J236D01*
G01Y968504D01*
G02X1008465Y985185I16681J0D01*
G01X1380315D01*
G02X1396996Y968504I0J-16681D01*
G01Y3937D01*
G02X1396063Y3004I-933J0D01*
G01X1210571D01*
G02X1209638Y3937I0J933D01*
G01Y171261D01*
G37*
G36*
G01X313750Y65189D02*
X316189Y62750D01*
X321189D01*
X323750Y60189D01*
Y28689D01*
X325750Y26689D01*
Y10811D01*
X324189Y9250D01*
X296811D01*
X296114Y9947D01*
Y62993D01*
G03X296110Y63225I-6941J-4D01*
G01Y64235D01*
X295976Y64368D01*
X295964Y64426D01*
G03X290607Y69783I-6791J-1434D01*
G01X290549Y69795D01*
X290416Y69929D01*
X289406D01*
G03X289174Y69933I-236J-6937D01*
G01X247835D01*
G02X246902Y70866I0J933D01*
G01Y224449D01*
G03X246898Y224681I-6941J-4D01*
G01Y225692D01*
X246764Y225826D01*
X246752Y225884D01*
G03X241396Y231240I-6791J-1435D01*
G01X241338Y231252D01*
X241204Y231386D01*
X240193D01*
G03X239961Y231390I-236J-6937D01*
G01X232250D01*
Y319811D01*
X150750Y401311D01*
Y580189D01*
X155355Y584794D01*
G03X158719Y587911I1545J1707D01*
G01X158611Y588050D01*
X230311Y659750D01*
X375619D01*
X375669Y659700D01*
X380169D01*
X383750Y656119D01*
Y603811D01*
X381689Y601750D01*
X243689D01*
X207750Y565811D01*
Y564879D01*
X207610Y564835D01*
G03Y560445I695J-2195D01*
G01X207750Y560401D01*
Y550909D01*
X207610Y550865D01*
G03Y546475I695J-2195D01*
G01X207750Y546431D01*
Y538559D01*
X207610Y538515D01*
G03Y534125I695J-2195D01*
G01X207750Y534081D01*
Y518864D01*
G03Y514260I23J-2302D01*
G01Y438189D01*
X210289Y435650D01*
X210262Y435541D01*
G03X213041Y432762I2238J-541D01*
G01X213150Y432789D01*
X280750Y365189D01*
Y311689D01*
X284189Y308250D01*
X292189D01*
X294250Y306189D01*
Y144189D01*
X313750Y124689D01*
Y104794D01*
X313586Y104764D01*
G03Y100236I414J-2264D01*
G01X313750Y100206D01*
Y65189D01*
G37*
G36*
G01X209250Y560541D02*
G03Y564739I-945J2099D01*
G01Y565189D01*
X244311Y600250D01*
X539119D01*
X542700Y596669D01*
Y518761D01*
X540189Y516250D01*
X511311D01*
X507750Y519811D01*
Y558311D01*
X485811Y580250D01*
X247689D01*
X221750Y554311D01*
Y442189D01*
X294250Y369689D01*
Y311811D01*
X292189Y309750D01*
X284811D01*
X282250Y312311D01*
Y365811D01*
X214388Y433673D01*
X214469Y433807D01*
G03X211307Y436969I-1969J1193D01*
G01X211173Y436888D01*
X209250Y438811D01*
Y514796D01*
G03Y518328I-1477J1766D01*
G01Y534221D01*
G03Y538419I-945J2099D01*
G01Y546571D01*
G03Y550769I-945J2099D01*
G01Y560541D01*
G37*
G36*
G01X328811Y9250D02*
X327250Y10811D01*
Y27311D01*
X325250Y29311D01*
Y60811D01*
X323245Y62816D01*
X323232Y62838D01*
G03X322338Y63732I-2232J-1338D01*
G01X322316Y63745D01*
X321811Y64250D01*
X316811D01*
X315250Y65811D01*
Y84110D01*
G03Y86390I-2000J1140D01*
G01Y100567D01*
G03Y104433I-1250J1933D01*
G01Y124689D01*
X316811Y126250D01*
X320089D01*
X321750Y124589D01*
Y116689D01*
X325189Y113250D01*
X364689D01*
X366689Y111250D01*
X366750D01*
Y88811D01*
X360750Y82811D01*
Y65926D01*
G03Y62074I1750J-1926D01*
G01Y53811D01*
X358689Y51750D01*
X343189D01*
X339250Y47811D01*
Y11311D01*
X337189Y9250D01*
X328811D01*
G37*
G36*
G01X369742Y150750D02*
X369741Y151443D01*
X369752Y151475D01*
G03X369172Y153199I-1423J481D01*
G02X369173Y153862I224J331D01*
G03X369144Y156372I-840J1245D01*
G02X369131Y157036I216J336D01*
G03X369702Y158726I-860J1232D01*
G01X369692Y158757D01*
X369728Y160861D01*
X369740Y160892D01*
G03X369147Y162658I-1414J508D01*
G02Y163328I218J335D01*
G03X369187Y165815I-822J1257D01*
G02X369189Y166471I230J327D01*
G03X369752Y168201I-855J1235D01*
G01X369741Y168232D01*
X369725Y170327D01*
X369735Y170358D01*
G03X366891Y170336I-1426J472D01*
G01X366902Y170304D01*
X366918Y168209D01*
X366908Y168178D01*
G03X367255Y166661I1426J-472D01*
G02X366971Y165983I-288J-278D01*
G01X365659Y165971D01*
X365627Y165981D01*
G03X365655Y163137I-469J-1427D01*
G01X365686Y163148D01*
X366993Y163160D01*
G02X367276Y162474I4J-400D01*
G03X366895Y160942I1050J-1074D01*
G01X366905Y160911D01*
X366869Y158807D01*
X366857Y158776D01*
G03X367215Y157200I1414J-508D01*
G02X366935Y156515I-281J-285D01*
G01X365651Y156513D01*
X365620Y156523D01*
G03X365626Y153679I-480J-1423D01*
G01X365658Y153690D01*
X366975Y153693D01*
G02X367260Y153011I1J-400D01*
G03X366907Y151471I1069J-1055D01*
G01X366918Y151440D01*
X366921Y149340D01*
X366910Y149308D01*
G03X366964Y148208I1423J-481D01*
G01X367021Y148082D01*
X366750Y147811D01*
Y116811D01*
X364689Y114750D01*
X353664D01*
G03X351336I-1164J-1750D01*
G01X325811D01*
X323384Y117177D01*
G03X323250Y119996I-1884J1323D01*
G01Y124689D01*
X324471Y125910D01*
X324609Y125814D01*
G03X327717Y126250I1320J1886D01*
G01X337167D01*
G03X339367Y128122I833J1250D01*
G01X339310Y128249D01*
X339750Y128689D01*
Y170689D01*
X354811Y185750D01*
X363952D01*
G03X366422I1235J855D01*
G01X381189D01*
X383250Y183689D01*
Y178404D01*
G03Y175836I780J-1284D01*
G01Y175285D01*
G03Y172721I782J-1282D01*
G01Y172165D01*
G03Y169611I791J-1277D01*
G01Y168985D01*
G03Y166421I782J-1282D01*
G01Y159534D01*
G03Y156998I805J-1268D01*
G01Y156385D01*
G03X382706Y154457I805J-1268D01*
G01X382768Y154329D01*
X379189Y150750D01*
X369742D01*
G37*
G36*
G01X463636Y174803D02*
X474250Y164189D01*
Y32811D01*
X450689Y9250D01*
X440794D01*
X440764Y9414D01*
G03X436236I-2264J-414D01*
G01X436206Y9250D01*
X415933D01*
G03X412067I-1933J-1250D01*
G01X342311D01*
X340750Y10811D01*
Y47189D01*
X343811Y50250D01*
X367504D01*
X367552Y50118D01*
G03X372448I2448J882D01*
G01X372496Y50250D01*
X391811D01*
X421750Y80189D01*
Y126998D01*
X421908Y127032D01*
G03Y129968I-318J1468D01*
G01X421750Y130002D01*
Y146811D01*
X420150Y148411D01*
X420171Y148517D01*
G03X418399Y150289I-1471J301D01*
G01X418293Y150268D01*
X416994Y151567D01*
X417017Y151673D01*
G03X415232Y153458I-1468J317D01*
G01X415126Y153435D01*
X413851Y154710D01*
X413873Y154815D01*
G03X412099Y156589I-1471J303D01*
G01X411994Y156567D01*
X409311Y159250D01*
X407238D01*
G03X404966I-1136J-983D01*
G01X397788D01*
G03X395518I-1135J-984D01*
G01X388374D01*
G03X386315Y159489I-1155J-960D01*
G01X386176Y159385D01*
X384750Y160811D01*
Y166384D01*
G03Y169022I-718J1319D01*
G01Y169564D01*
G03Y172212I-709J1324D01*
G01Y172684D01*
G03Y175322I-718J1319D01*
G01Y175802D01*
G03Y178438I-720J1318D01*
G01Y185281D01*
G03Y187945I-695J1332D01*
G01Y188426D01*
G03Y191068I-714J1321D01*
G01Y191580D01*
G03Y194244I-695J1332D01*
G01Y194730D01*
G03X385261Y196958I-695J1332D01*
G01X385158Y197097D01*
X386811Y198750D01*
X395217D01*
X395269Y198628D01*
G03X398037I1384J583D01*
G01X398089Y198750D01*
X423563D01*
X423615Y198628D01*
G03X426383I1384J583D01*
G01X426435Y198750D01*
X426713D01*
X426765Y198628D01*
G03X429533I1384J583D01*
G01X429585Y198750D01*
X433014D01*
X433065Y198628D01*
G03X435833I1384J584D01*
G01X435884Y198750D01*
X436163D01*
X436214Y198628D01*
G03X438982I1384J584D01*
G01X439033Y198750D01*
X439689D01*
X442393Y196046D01*
X442398Y195970D01*
G03X443804Y194564I1499J93D01*
G01X443880Y194559D01*
X448692Y189747D01*
X448697Y189671D01*
G03X450103Y188265I1499J93D01*
G01X450179Y188260D01*
X460582Y177857D01*
X460534Y177736D01*
G03X463515Y174755I2145J-836D01*
G01X463636Y174803D01*
G37*
G36*
G01X364250Y51750D02*
Y51811D01*
X362250Y53811D01*
Y82189D01*
X368250Y88189D01*
Y134551D01*
G02X368432Y134750I200J0D01*
G03X368768Y134820I-136J1496D01*
G01X368799Y134830D01*
X370930Y134814D01*
X370962Y134803D01*
G03X370984Y137647I494J1418D01*
G01X370953Y137637D01*
X369637Y137647D01*
G02X369360Y138332I4J400D01*
G03X369729Y139880I-1055J1069D01*
G01X369718Y139911D01*
X369724Y141986D01*
X369735Y142018D01*
G03X369366Y143577I-1421J487D01*
G02X369647Y144263I280J286D01*
G01X370973Y144258D01*
X371004Y144247D01*
G03X371016Y147091I489J1420D01*
G01X370984Y147081D01*
X369680Y147086D01*
G02X369398Y147768I2J400D01*
G03X369830Y148702I-1065J1059D01*
G01X369836Y148775D01*
X370311Y149250D01*
X379811D01*
X384180Y153619D01*
X384247Y153627D01*
G03X385189Y156102I-192J1490D01*
G02X385208Y156647I302J262D01*
G01X385694Y157133D01*
G02X386238Y157153I283J-283D01*
G03X388572Y157637I981J1137D01*
G01X388626Y157750D01*
X395237D01*
X395290Y157634D01*
G03X398016I1363J632D01*
G01X398069Y157750D01*
X404686D01*
X404740Y157634D01*
G03X407464I1362J633D01*
G01X407518Y157750D01*
X408689D01*
X410944Y155495D01*
X410925Y155391D01*
G03X412675Y153641I1477J-273D01*
G01X412779Y153660D01*
X414087Y152352D01*
X414070Y152249D01*
G03X415808Y150511I1479J-259D01*
G01X415911Y150528D01*
X417243Y149196D01*
X417223Y149093D01*
G03X418975Y147341I1477J-275D01*
G01X419078Y147361D01*
X420250Y146189D01*
Y129180D01*
X420231Y129140D01*
G03Y127860I1359J-640D01*
G01X420250Y127820D01*
Y80811D01*
X391189Y51750D01*
X372496D01*
X372448Y51882D01*
G03X367552I-2448J-882D01*
G01X367504Y51750D01*
X364250D01*
G37*
%LPD*%
G75*
G36*
G01X1379639Y609381D02*
G03Y608848I298J-266D01*
G02X1376353I-1643J-1466D01*
G03Y609381I-298J267D01*
G02X1379639I1643J1466D01*
G37*
G36*
G01X1382336Y600343D02*
Y600007D01*
X1382402Y599948D01*
G02X1379448I-1477J-1633D01*
G01X1379514Y600007D01*
Y600343D01*
X1379448Y600402D01*
G02X1382402I1477J1633D01*
G01X1382336Y600343D01*
G37*
G36*
G01X1383443Y579784D02*
X1383107D01*
X1383048Y579718D01*
G02Y582672I-1633J1477D01*
G01X1383107Y582606D01*
X1383443D01*
X1383502Y582672D01*
G02Y579718I1633J-1477D01*
G01X1383443Y579784D01*
G37*
G36*
G01X1362874Y624709D02*
X1362779Y624718D01*
X1349615Y611554D01*
G02X1346600Y608347I-1999J-1142D01*
G01X1346471Y608410D01*
X1308811Y570750D01*
X1151811D01*
X1149750Y568689D01*
Y542487D01*
X1149754Y542467D01*
G02Y541533I-2254J-467D01*
G01X1149750Y541513D01*
Y498689D01*
X1145811Y494750D01*
X1005189D01*
X965309Y534630D01*
G02X961630Y538309I-1809J1870D01*
G01X939750Y560189D01*
Y662811D01*
X944189Y667250D01*
X1004689D01*
X1006750Y669311D01*
Y709811D01*
X1049189Y752250D01*
X1324311D01*
X1363250Y713311D01*
Y629304D01*
X1363422Y629279D01*
G02X1362874Y624709I-322J-2279D01*
G37*
G36*
G01X422080Y408344D02*
Y405437D01*
X422090Y405405D01*
G02X419246I-1422J-483D01*
G01X419256Y405437D01*
Y408344D01*
X419246Y408376D01*
G02X422090I1422J483D01*
G01X422080Y408344D01*
G37*
G36*
G01X74347Y386464D02*
X73619D01*
G02Y389488I-1736J1512D01*
G01X74347D01*
G02Y386464I1736J-1512D01*
G37*
G36*
G01X64795Y386309D02*
X64553Y386302D01*
X64496Y386238D01*
G02X64410Y389404I-1713J1538D01*
G01X64471Y389343D01*
X64713Y389350D01*
X64770Y389414D01*
G02X64856Y386248I1713J-1538D01*
G01X64795Y386309D01*
G37*
G36*
G01X45413Y389489D02*
G03X45946Y389490I266J299D01*
G02X45953Y386056I1537J-1714D01*
G03X45420Y386055I-266J-299D01*
G02X45413Y389489I-1537J1714D01*
G37*
G36*
G01X55229Y386273D02*
X55000Y386260D01*
X54945Y386194D01*
G02X54774Y389339I-1762J1481D01*
G01X54837Y389279D01*
X55066Y389292D01*
X55122Y389358D01*
G02X55291Y386213I1761J-1482D01*
G01X55229Y386273D01*
G37*
G36*
G01X164909Y353198D02*
X164539D01*
X164480Y353134D01*
G02Y356284I-1679J1575D01*
G01X164539Y356220D01*
X164909D01*
X164968Y356284D01*
G02Y353134I1679J-1575D01*
G01X164909Y353198D01*
G37*
G36*
G01X153409D02*
X153039D01*
X152980Y353134D01*
G02Y356284I-1679J1575D01*
G01X153039Y356220D01*
X153409D01*
X153468Y356284D01*
G02Y353134I1679J-1575D01*
G01X153409Y353198D01*
G37*
G36*
G01X141409D02*
X141039D01*
X140980Y353134D01*
G02Y356284I-1679J1575D01*
G01X141039Y356220D01*
X141409D01*
X141468Y356284D01*
G02Y353134I1679J-1575D01*
G01X141409Y353198D01*
G37*
G36*
G01X129409D02*
X129039D01*
X128980Y353134D01*
G02Y356284I-1679J1575D01*
G01X129039Y356220D01*
X129409D01*
X129468Y356284D01*
G02Y353134I1679J-1575D01*
G01X129409Y353198D01*
G37*
G36*
G01X528012Y356000D02*
Y353501D01*
X528022Y353470D01*
G02X524978I-1522J-501D01*
G01X524988Y353501D01*
Y356000D01*
X524978Y356031D01*
G02X528022I1522J501D01*
G01X528012Y356000D01*
G37*
G36*
G01X1198147Y342875D02*
G03X1197613I-267J-298D01*
G02Y346301I-1538J1713D01*
G03X1198147I267J298D01*
G02Y342875I1538J-1713D01*
G37*
G36*
G01X528012Y346000D02*
Y343501D01*
X528022Y343470D01*
G02X524978I-1522J-501D01*
G01X524988Y343501D01*
Y346000D01*
X524978Y346031D01*
G02X528022I1522J501D01*
G01X528012Y346000D01*
G37*
G36*
G01X194386Y343719D02*
Y343349D01*
X194449Y343290D01*
G02X191299I-1575J-1679D01*
G01X191362Y343349D01*
Y343719D01*
X191299Y343778D01*
G02X194449I1575J1679D01*
G01X194386Y343719D01*
G37*
G36*
G01Y332569D02*
Y332199D01*
X194449Y332140D01*
G02X191299I-1575J-1679D01*
G01X191362Y332199D01*
Y332569D01*
X191299Y332628D01*
G02X194449I1575J1679D01*
G01X194386Y332569D01*
G37*
G36*
G01X177884Y327238D02*
X177514D01*
X177455Y327174D01*
G02Y330324I-1679J1575D01*
G01X177514Y330260D01*
X177884D01*
X177943Y330324D01*
G02Y327174I1679J-1575D01*
G01X177884Y327238D01*
G37*
G36*
G01X166255Y327188D02*
X165885D01*
X165826Y327124D01*
G02Y330274I-1679J1575D01*
G01X165885Y330210D01*
X166255D01*
X166314Y330274D01*
G02Y327124I1679J-1575D01*
G01X166255Y327188D01*
G37*
G36*
G01X532970Y323988D02*
X530380D01*
X530349Y323978D01*
G02Y327022I-501J1522D01*
G01X530380Y327012D01*
X532970D01*
X533001Y327022D01*
G02Y323978I501J-1522D01*
G01X532970Y323988D01*
G37*
G36*
G01X1171587Y322003D02*
G03X1171053I-267J-298D01*
G02Y325429I-1538J1713D01*
G03X1171587I267J298D01*
G02Y322003I1538J-1713D01*
G37*
G36*
G01X157386Y325219D02*
Y324849D01*
X157449Y324790D01*
G02X154299I-1575J-1679D01*
G01X154362Y324849D01*
Y325219D01*
X154299Y325278D01*
G02X157449I1575J1679D01*
G01X157386Y325219D01*
G37*
G36*
G01X538082Y319488D02*
X535492D01*
X535461Y319478D01*
G02Y322522I-501J1522D01*
G01X535492Y322512D01*
X538082D01*
X538113Y322522D01*
G02Y319478I501J-1522D01*
G01X538082Y319488D01*
G37*
G36*
G01X511468Y318488D02*
X509032D01*
X509001Y318478D01*
G02Y321522I-501J1522D01*
G01X509032Y321512D01*
X511468D01*
X511499Y321522D01*
G02Y318478I501J-1522D01*
G01X511468Y318488D01*
G37*
G36*
G01X1254788Y322854D02*
Y322146D01*
X1254844Y322088D01*
G02X1251510I-1667J-1588D01*
G01X1251566Y322146D01*
Y322854D01*
X1251510Y322912D01*
G02X1254844I1667J1588D01*
G01X1254788Y322854D01*
G37*
G36*
G01X526470Y317848D02*
X523880D01*
X523849Y317837D01*
G02Y320881I-501J1522D01*
G01X523880Y320870D01*
X526470D01*
X526501Y320881D01*
G02Y317837I501J-1522D01*
G01X526470Y317848D01*
G37*
G36*
G01X494571Y314440D02*
X491789D01*
X491758Y314430D01*
G02Y317474I-501J1522D01*
G01X491789Y317464D01*
X494571D01*
X494602Y317474D01*
G02Y314430I501J-1522D01*
G01X494571Y314440D01*
G37*
G36*
G01X502715Y312688D02*
X502345D01*
X502286Y312625D01*
G02Y315775I-1679J1575D01*
G01X502345Y315712D01*
X502715D01*
X502774Y315775D01*
G02Y312625I1679J-1575D01*
G01X502715Y312688D01*
G37*
G36*
G01X517968Y312488D02*
X517598D01*
X517539Y312425D01*
G02Y315575I-1679J1575D01*
G01X517598Y315512D01*
X517968D01*
X518027Y315575D01*
G02Y312425I1679J-1575D01*
G01X517968Y312488D01*
G37*
G36*
G01X157386Y316069D02*
Y315699D01*
X157449Y315640D01*
G02X154299I-1575J-1679D01*
G01X154362Y315699D01*
Y316069D01*
X154299Y316128D01*
G02X157449I1575J1679D01*
G01X157386Y316069D01*
G37*
G36*
G01X1157813Y314867D02*
G03Y314333I298J-267D01*
G02X1154387I-1713J-1538D01*
G03Y314867I-298J267D01*
G02X1157813I1713J1538D01*
G37*
G36*
G01X1251863Y310336D02*
X1251916Y310395D01*
X1251897Y311124D01*
X1251842Y311180D01*
G02X1255191Y311264I1635J1620D01*
G01X1255138Y311205D01*
X1255157Y310476D01*
X1255212Y310420D01*
G02X1251863Y310336I-1635J-1620D01*
G37*
G36*
G01X1166713Y306637D02*
G03Y306103I298J-267D01*
G02X1163287I-1713J-1538D01*
G03Y306637I-298J267D01*
G02X1166713I1713J1538D01*
G37*
G36*
G01X805070Y301738D02*
X804680D01*
X804621Y301675D01*
G02Y304825I-1679J1575D01*
G01X804680Y304762D01*
X805070D01*
X805129Y304825D01*
G02Y301675I1679J-1575D01*
G01X805070Y301738D01*
G37*
G36*
G01X789320D02*
X788930D01*
X788871Y301675D01*
G02Y304825I-1679J1575D01*
G01X788930Y304762D01*
X789320D01*
X789379Y304825D01*
G02Y301675I1679J-1575D01*
G01X789320Y301738D01*
G37*
G36*
G01X773575D02*
X773185D01*
X773126Y301675D01*
G02Y304825I-1679J1575D01*
G01X773185Y304762D01*
X773575D01*
X773634Y304825D01*
G02Y301675I1679J-1575D01*
G01X773575Y301738D01*
G37*
G36*
G01X757825D02*
X757435D01*
X757376Y301675D01*
G02Y304825I-1679J1575D01*
G01X757435Y304762D01*
X757825D01*
X757884Y304825D01*
G02Y301675I1679J-1575D01*
G01X757825Y301738D01*
G37*
G36*
G01X663335D02*
X662945D01*
X662886Y301675D01*
G02Y304825I-1679J1575D01*
G01X662945Y304762D01*
X663335D01*
X663394Y304825D01*
G02Y301675I1679J-1575D01*
G01X663335Y301738D01*
G37*
G36*
G01X647585D02*
X647195D01*
X647136Y301675D01*
G02Y304825I-1679J1575D01*
G01X647195Y304762D01*
X647585D01*
X647644Y304825D01*
G02Y301675I1679J-1575D01*
G01X647585Y301738D01*
G37*
G36*
G01X631840D02*
X631450D01*
X631391Y301675D01*
G02Y304825I-1679J1575D01*
G01X631450Y304762D01*
X631840D01*
X631899Y304825D01*
G02Y301675I1679J-1575D01*
G01X631840Y301738D01*
G37*
G36*
G01X616090D02*
X615700D01*
X615641Y301675D01*
G02Y304825I-1679J1575D01*
G01X615700Y304762D01*
X616090D01*
X616149Y304825D01*
G02Y301675I1679J-1575D01*
G01X616090Y301738D01*
G37*
G36*
G01X432664Y343352D02*
X432769Y343330D01*
X434952Y345513D01*
X434935Y345615D01*
G02X436666Y347346I1481J250D01*
G01X436768Y347329D01*
X438889Y349450D01*
X438872Y349552D01*
G02X441742Y350374I1481J250D01*
G01X441793Y350250D01*
X442850D01*
X442901Y350374D01*
G02X445679I1389J-572D01*
G01X445730Y350250D01*
X446787D01*
X446838Y350374D01*
G02X449616I1389J-572D01*
G01X449667Y350250D01*
X450881D01*
G02X453449I1284J-780D01*
G01X454374D01*
X454423Y350378D01*
G02X457227I1402J-538D01*
G01X457276Y350250D01*
X458811D01*
X461750Y347311D01*
Y316689D01*
X444311Y299250D01*
X433996D01*
G02X431004I-1496J1750D01*
G01X379990D01*
G02X375720I-2135J860D01*
G01X330189D01*
X326750Y302689D01*
Y305706D01*
X326586Y305736D01*
G02Y310264I414J2264D01*
G01X326750Y310294D01*
Y332311D01*
X330689Y336250D01*
X392242D01*
G02X395868I1813J-1250D01*
G01X425689D01*
X427078Y337639D01*
X427061Y337741D01*
G02X428792Y339472I1481J250D01*
G01X428894Y339455D01*
X430915Y341476D01*
X430893Y341581D01*
G02X432664Y343352I1472J299D01*
G37*
G36*
G01X1262188Y298322D02*
Y297748D01*
X1262244Y297690D01*
G02X1258910I-1667J-1588D01*
G01X1258966Y297748D01*
Y298322D01*
X1258910Y298380D01*
G02X1262244I1667J1588D01*
G01X1262188Y298322D01*
G37*
G36*
G01X211995Y293398D02*
X211625D01*
X211566Y293334D01*
G02Y296484I-1679J1575D01*
G01X211625Y296420D01*
X211995D01*
X212054Y296484D01*
G02Y293334I1679J-1575D01*
G01X211995Y293398D01*
G37*
G36*
G01X202547D02*
X202177D01*
X202118Y293334D01*
G02Y296484I-1679J1575D01*
G01X202177Y296420D01*
X202547D01*
X202606Y296484D01*
G02Y293334I1679J-1575D01*
G01X202547Y293398D01*
G37*
G36*
G01X177350D02*
X176980D01*
X176921Y293334D01*
G02Y296484I-1679J1575D01*
G01X176980Y296420D01*
X177350D01*
X177409Y296484D01*
G02Y293334I1679J-1575D01*
G01X177350Y293398D01*
G37*
G36*
G01X167901Y292798D02*
X167531D01*
X167472Y292734D01*
G02Y295884I-1679J1575D01*
G01X167531Y295820D01*
X167901D01*
X167960Y295884D01*
G02Y292734I1679J-1575D01*
G01X167901Y292798D01*
G37*
G36*
G01X1172039Y288614D02*
X1171515D01*
X1171456Y288550D01*
G02Y291700I-1679J1575D01*
G01X1171515Y291636D01*
X1172039D01*
X1172098Y291700D01*
G02Y288550I1679J-1575D01*
G01X1172039Y288614D01*
G37*
G36*
G01X1191005Y288288D02*
X1190615D01*
X1190556Y288225D01*
G02Y291375I-1679J1575D01*
G01X1190615Y291312D01*
X1191005D01*
X1191064Y291375D01*
G02Y288225I1679J-1575D01*
G01X1191005Y288288D01*
G37*
G36*
G01X1252288Y285854D02*
Y285146D01*
X1252344Y285088D01*
G02X1249010I-1667J-1588D01*
G01X1249066Y285146D01*
Y285854D01*
X1249010Y285912D01*
G02X1252344I1667J1588D01*
G01X1252288Y285854D01*
G37*
G36*
G01X1256456Y270695D02*
Y270305D01*
X1256519Y270246D01*
G02X1253369I-1575J-1679D01*
G01X1253432Y270305D01*
Y270695D01*
X1253369Y270754D01*
G02X1256519I1575J1679D01*
G01X1256456Y270695D01*
G37*
G36*
G01X830531Y402807D02*
G02X833823Y405884I1969J1193D01*
G01X834689Y406750D01*
X844706D01*
X844736Y406914D01*
G02X849264I2264J-414D01*
G01X849294Y406750D01*
X854311D01*
X865311Y395750D01*
X945311D01*
X953750Y387311D01*
Y351221D01*
X953914Y351191D01*
G02Y346663I-414J-2264D01*
G01X953750Y346633D01*
Y214189D01*
X949811Y210250D01*
X922189D01*
X917750Y214689D01*
Y324689D01*
X902189Y340250D01*
X831689D01*
X824750Y347189D01*
Y396811D01*
X830612Y402673D01*
X830531Y402807D01*
G37*
G36*
G01X309166Y162288D02*
X306384D01*
X306353Y162278D01*
G02Y165322I-501J1522D01*
G01X306384Y165312D01*
X309166D01*
X309197Y165322D01*
G02Y162278I501J-1522D01*
G01X309166Y162288D01*
G37*
G36*
G01X316716Y154488D02*
X313934D01*
X313903Y154478D01*
G02Y157522I-501J1522D01*
G01X313934Y157512D01*
X316716D01*
X316747Y157522D01*
G02Y154478I501J-1522D01*
G01X316716Y154488D01*
G37*
G36*
G01X327934Y151975D02*
Y149476D01*
X327944Y149445D01*
G02X324900I-1522J-501D01*
G01X324910Y149476D01*
Y151975D01*
X324900Y152006D01*
G02X327944I1522J501D01*
G01X327934Y151975D01*
G37*
G36*
G01X329512Y149097D02*
X329522Y149127D01*
X329606Y152153D01*
X329597Y152183D01*
G02X332457Y152104I1443J418D01*
G01X332447Y152074D01*
X332363Y149048D01*
X332372Y149018D01*
G02X329512Y149097I-1443J-418D01*
G37*
G36*
G01X321312Y146366D02*
Y143584D01*
X321322Y143553D01*
G02X318278I-1522J-501D01*
G01X318288Y143584D01*
Y146366D01*
X318278Y146397D01*
G02X321322I1522J501D01*
G01X321312Y146366D01*
G37*
G36*
G01X328612Y139325D02*
Y136826D01*
X328622Y136795D01*
G02X325578I-1522J-501D01*
G01X325588Y136826D01*
Y139325D01*
X325578Y139356D01*
G02X328622I1522J501D01*
G01X328612Y139325D01*
G37*
G36*
G01X1092156Y124988D02*
X1091766D01*
X1091707Y124925D01*
G02Y128075I-1679J1575D01*
G01X1091766Y128012D01*
X1092156D01*
X1092215Y128075D01*
G02Y124925I1679J-1575D01*
G01X1092156Y124988D01*
G37*
G36*
G01X1072448Y40156D02*
X1069284D01*
G02Y46378I-2355J3111D01*
G01X1072448D01*
G02Y40156I2355J-3111D01*
G37*
G36*
G01X487888Y320184D02*
G02X487071Y317098I-276J-1578D01*
G01X487040Y317109D01*
X484435Y317176D01*
X484403Y317166D01*
G02X483299Y319951I-448J1434D01*
G03X483309Y320666I-174J360D01*
G02X483167Y320750I693J1333D01*
G01X477689D01*
X475750Y322689D01*
Y328605D01*
X475578Y328630D01*
G02Y331604I210J1487D01*
G01X475750Y331629D01*
Y340416D01*
X475578Y340441D01*
G02Y343415I210J1487D01*
G01X475750Y343440D01*
Y348290D01*
X475578Y348315D01*
G02Y351289I210J1487D01*
G01X475750Y351314D01*
Y356164D01*
X475578Y356189D01*
G02Y359163I210J1487D01*
G01X475750Y359188D01*
Y360101D01*
X475578Y360126D01*
G02Y363100I210J1487D01*
G01X475750Y363125D01*
Y367975D01*
X475578Y368000D01*
G02Y370974I210J1487D01*
G01X475750Y370999D01*
Y375851D01*
X475578Y375876D01*
G02X474817Y378509I210J1487D01*
G03X474842Y379097I-258J306D01*
G01X467750Y386189D01*
Y387672D01*
X467593Y387707D01*
G02Y390641I321J1467D01*
G01X467750Y390676D01*
Y391609D01*
X467593Y391644D01*
G02X466810Y394129I321J1467D01*
G01X464995Y395944D01*
G02X462494Y397287I-1018J1104D01*
G03X462099Y397750I-395J63D01*
G01X425189D01*
X423250Y399689D01*
Y400336D01*
X423233Y400374D01*
G02Y401596I1372J611D01*
G01X423250Y401634D01*
Y404273D01*
X423233Y404311D01*
G02X423183Y405405I1372J611D01*
G01X423194Y405437D01*
Y408344D01*
X423183Y408376D01*
G02X423233Y409470I1422J483D01*
G01X423250Y409508D01*
Y411189D01*
X422250Y412189D01*
Y426189D01*
X418250Y430189D01*
Y449311D01*
X420189Y451250D01*
X591311D01*
X595250Y447311D01*
Y375689D01*
X591311Y371750D01*
X529811D01*
X521663Y363602D01*
G02X522022Y361999I-1163J-1102D01*
G01X522012Y361968D01*
Y359469D01*
X522022Y359438D01*
G02X520620Y357340I-1522J-501D01*
G03X520250Y356941I30J-399D01*
G01Y353496D01*
G03X520620Y353097I400J0D01*
G02X522022Y350999I-120J-1597D01*
G01X522012Y350968D01*
Y348469D01*
X522022Y348438D01*
G02X520620Y346340I-1522J-501D01*
G03X520250Y345941I30J-399D01*
G01Y336189D01*
X502311Y318250D01*
X493689D01*
X491189Y320750D01*
X488121D01*
G02X487833Y320559I-969J1148D01*
G03X487888Y320184I90J-178D01*
G37*
G36*
G01X373190Y139908D02*
X373194Y142009D01*
X373184Y142040D01*
G02X375851Y143362I1423J480D01*
G03X376513I331J224D01*
G02X379178Y142034I1244J-842D01*
G01X379167Y142002D01*
X379163Y139911D01*
X379173Y139880D01*
G02X376509Y138554I-1423J-480D01*
G03X375846Y138552I-331J-225D01*
G02X373179Y139876I-1246J839D01*
G01X373190Y139908D01*
G37*
G36*
G01X385266Y138533D02*
G02X382603Y139871I-1247J838D01*
G01X382614Y139902D01*
X382638Y142022D01*
X382628Y142054D01*
G02X385300Y143362I1428J466D01*
G03X385962I331J224D01*
G02X388623Y142022I1244J-842D01*
G01X388612Y141991D01*
X388590Y139875D01*
X388600Y139844D01*
G02X385929Y138534I-1427J-468D01*
G03X385266Y138533I-331J-224D01*
G37*
G36*
G01X401542Y139885D02*
Y142006D01*
X401532Y142037D01*
G02X404197Y143363I1422J483D01*
G03X404860I331J224D01*
G02X407525Y142037I1243J-843D01*
G01X407514Y142005D01*
Y139886D01*
X407525Y139854D01*
G02X404859Y138529I-1422J-483D01*
G03X404197Y138528I-331J-225D01*
G02X401531Y139854I-1244J842D01*
G01X401542Y139885D01*
G37*
G36*
G01X394769Y138520D02*
G02X392087Y139821I-1259J819D01*
G01X392098Y139852D01*
X392094Y142003D01*
X392084Y142035D01*
G02X394749Y143362I1421J485D01*
G03X395411I331J224D01*
G02X398081Y142050I1243J-842D01*
G01X398071Y142018D01*
X398090Y139889D01*
X398101Y139858D01*
G02X395436Y138525I-1418J-496D01*
G03X394769Y138520I-332J-223D01*
G37*
G54D60*
X1272441Y7087D03*
X1299213D03*
G54D58*
X1224016Y180709D03*
G54D57*
X968819Y380000D03*
G54D61*
X1379862Y108465D03*
Y119095D03*
G54D59*
X1224016Y386221D03*
G54D52*
X35435Y373228D03*
X82675D03*
G54D51*
X21220D03*
X96890D03*
X157480Y283071D03*
X220472D03*
G54D49*
X1227165Y411417D03*
X1227166Y155511D03*
X1008268Y411417D03*
G54D50*
Y244094D03*
G54D56*
X743897Y353543D03*
Y410629D03*
X1305117Y87548D03*
Y262745D03*
X1376968Y147243D03*
Y216535D03*
X490944Y255118D03*
Y79921D03*
X270078Y92125D03*
Y155117D03*
G54D55*
X600925Y44134D03*
X638917D03*
G54D54*
X537994Y303150D03*
X825984D03*
G54D53*
X332086Y408858D03*
X450196Y257874D03*
X572243Y337992D03*
X355708Y96456D03*
%LPC*%
G75*
G36*
G01X437859Y346298D02*
X439920Y348359D01*
X440028Y348336D01*
G03X441425Y348750I325J1466D01*
G01X443218D01*
G03X445362I1072J1052D01*
G01X447155D01*
G03X449299I1072J1052D01*
G01X450847D01*
G03X453483I1318J720D01*
G01X454792D01*
G03X456858I1033J1090D01*
G01X458189D01*
X460250Y346689D01*
Y317311D01*
X443689Y300750D01*
X380071D01*
X380023Y300883D01*
G03X375687I-2168J-773D01*
G01X375639Y300750D01*
X330811D01*
X328250Y303311D01*
Y306067D01*
G03Y309933I-1250J1933D01*
G01Y331689D01*
X331311Y334750D01*
X339781D01*
G03X342921I1570J1684D01*
G01X344433D01*
G03X347425I1496J1750D01*
G01X391861D01*
X391892Y334587D01*
G03X396218I2163J413D01*
G01X396249Y334750D01*
X426311D01*
X428109Y336548D01*
X428217Y336525D01*
G03X430008Y338316I325J1466D01*
G01X429985Y338424D01*
X431984Y340423D01*
X432088Y340404D01*
G03X433841Y342157I277J1476D01*
G01X433822Y342261D01*
X435983Y344422D01*
X436091Y344399D01*
G03X437882Y346190I325J1466D01*
G01X437859Y346298D01*
G37*
G36*
G01X529189Y373250D02*
X519942Y364002D01*
X519904Y363987D01*
G03X519013Y363096I596J-1487D01*
G01X518998Y363058D01*
X518750Y362811D01*
Y336811D01*
X501689Y319750D01*
X494311D01*
X491811Y322250D01*
X488623D01*
X488576Y322385D01*
G03X486743Y323344I-1421J-485D01*
G01X486713Y323336D01*
X484532Y323405D01*
X484502Y323416D01*
G03X482551Y322397I-502J-1416D01*
G01X482511Y322250D01*
X478311D01*
X477250Y323311D01*
Y329772D01*
X477255Y329793D01*
G03Y330441I-1467J324D01*
G01X477250Y330462D01*
Y341583D01*
X477255Y341604D01*
G03Y342252I-1467J324D01*
G01X477250Y342273D01*
Y349457D01*
X477255Y349478D01*
G03Y350126I-1467J324D01*
G01X477250Y350147D01*
Y357331D01*
X477255Y357352D01*
G03Y358000I-1467J324D01*
G01X477250Y358021D01*
Y361268D01*
X477255Y361289D01*
G03Y361937I-1467J324D01*
G01X477250Y361958D01*
Y369142D01*
X477255Y369163D01*
G03Y369811I-1467J324D01*
G01X477250Y369832D01*
Y377018D01*
X477255Y377039D01*
G03Y377687I-1467J324D01*
G01X477250Y377708D01*
Y378811D01*
X469250Y386811D01*
Y388486D01*
X469270Y388527D01*
G03Y389821I-1356J647D01*
G01X469250Y389862D01*
Y392423D01*
X469270Y392464D01*
G03Y393758I-1356J647D01*
G01X469250Y393799D01*
Y393811D01*
X469235Y393826D01*
G03X468629Y394432I-1321J-715D01*
G01X465298Y397763D01*
G03X464692Y398369I-1321J-715D01*
G01X463811Y399250D01*
X425811D01*
X425685Y399376D01*
G02X425681Y399937I283J283D01*
G03X424909Y402456I-1076J1048D01*
G01X424750Y402489D01*
Y403418D01*
X424909Y403451D01*
G03X426027Y405405I-304J1471D01*
G01X426016Y405437D01*
Y408344D01*
X426027Y408376D01*
G03X424909Y410330I-1422J483D01*
G01X424750Y410363D01*
Y411811D01*
X423750Y412811D01*
Y426811D01*
X419750Y430811D01*
Y448689D01*
X420811Y449750D01*
X590689D01*
X593750Y446689D01*
Y376311D01*
X590689Y373250D01*
X529189D01*
G37*
G36*
G01X922811Y211750D02*
X919250Y215311D01*
Y325311D01*
X902811Y341750D01*
X832311D01*
X826250Y347811D01*
Y396189D01*
X831850Y401789D01*
X831959Y401762D01*
G03X834738Y404541I541J2238D01*
G01X834711Y404650D01*
X835311Y405250D01*
X845067D01*
G03X848933I1933J1250D01*
G01X853689D01*
X864689Y394250D01*
X878193D01*
G03X880807I1307J2250D01*
G01X882693D01*
G03X885307I1307J2250D01*
G01X944689D01*
X952250Y386689D01*
Y350860D01*
G03Y346994I1250J-1933D01*
G01Y214811D01*
X949189Y211750D01*
X922811D01*
G37*
G36*
G01X1005811Y496250D02*
X966056Y536005D01*
X966072Y536105D01*
G03X963105Y539072I-2572J395D01*
G01X963005Y539056D01*
X941250Y560811D01*
Y662189D01*
X944811Y665750D01*
X988074D01*
G03X991926I1926J1750D01*
G01X998574D01*
G03X1002426I1926J1750D01*
G01X1004689D01*
X1006750Y663689D01*
Y604189D01*
X1040189Y570750D01*
X1146189D01*
X1148250Y568689D01*
Y499311D01*
X1145189Y496250D01*
X1005811D01*
G37*
G36*
G01X1323689Y750750D02*
X1361750Y712689D01*
Y628865D01*
G03X1361394Y625455I1350J-1865D01*
G01X1348486Y612547D01*
X1348368Y612588D01*
G03X1345441Y609661I-751J-2176D01*
G01X1345482Y609543D01*
X1308189Y572250D01*
X1127205D01*
G03X1123995I-1605J-1650D01*
G01X1040811D01*
X1008250Y604811D01*
Y709189D01*
X1023774Y724713D01*
X1023840Y724723D01*
G03X1025777Y726660I-340J2277D01*
G01X1025787Y726726D01*
X1049811Y750750D01*
X1105293D01*
G03X1107907I1307J2250D01*
G01X1125183D01*
G03X1127237I1027J2060D01*
G01X1132282D01*
X1132309Y750742D01*
G03X1133611I651J2208D01*
G01X1133638Y750750D01*
X1323689D01*
G37*
%LPD*%
G75*
G36*
G01X469326Y408344D02*
Y405437D01*
X469336Y405405D01*
G02X466492I-1422J-483D01*
G01X466502Y405437D01*
Y408344D01*
X466492Y408376D01*
G02X469336I1422J483D01*
G01X469326Y408344D01*
G37*
G36*
G01X465388D02*
Y405437D01*
X465399Y405405D01*
G02X462555I-1422J-483D01*
G01X462566Y405437D01*
Y408344D01*
X462555Y408376D01*
G02X465399I1422J483D01*
G01X465388Y408344D01*
G37*
G36*
G01X449638D02*
Y405437D01*
X449649Y405405D01*
G02X446805I-1422J-483D01*
G01X446816Y405437D01*
Y408344D01*
X446805Y408376D01*
G02X449649I1422J483D01*
G01X449638Y408344D01*
G37*
G36*
G01X445702D02*
Y405437D01*
X445712Y405405D01*
G02X442868I-1422J-483D01*
G01X442878Y405437D01*
Y408344D01*
X442868Y408376D01*
G02X445712I1422J483D01*
G01X445702Y408344D01*
G37*
G36*
G01X441764D02*
Y405437D01*
X441775Y405405D01*
G02X438931I-1422J-483D01*
G01X438942Y405437D01*
Y408344D01*
X438931Y408376D01*
G02X441775I1422J483D01*
G01X441764Y408344D01*
G37*
G36*
G01X437828D02*
Y405437D01*
X437838Y405405D01*
G02X434994I-1422J-483D01*
G01X435004Y405437D01*
Y408344D01*
X434994Y408376D01*
G02X437838I1422J483D01*
G01X437828Y408344D01*
G37*
G36*
G01X433890D02*
Y405437D01*
X433901Y405405D01*
G02X431057I-1422J-483D01*
G01X431068Y405437D01*
Y408344D01*
X431057Y408376D01*
G02X433901I1422J483D01*
G01X433890Y408344D01*
G37*
G36*
G01X429954D02*
Y405437D01*
X429964Y405405D01*
G02X427120I-1422J-483D01*
G01X427130Y405437D01*
Y408344D01*
X427120Y408376D01*
G02X429964I1422J483D01*
G01X429954Y408344D01*
G37*
G36*
G01X457634Y408268D02*
Y405398D01*
X457645Y405366D01*
G02X454801I-1422J-483D01*
G01X454812Y405398D01*
Y408268D01*
X454801Y408300D01*
G02X457645I1422J483D01*
G01X457634Y408268D01*
G37*
G36*
G01X453634D02*
Y405398D01*
X453645Y405366D01*
G02X450801I-1422J-483D01*
G01X450812Y405398D01*
Y408268D01*
X450801Y408300D01*
G02X453645I1422J483D01*
G01X453634Y408268D01*
G37*
G36*
G01X484136Y370835D02*
X484168Y370825D01*
X487061Y370884D01*
X487092Y370895D01*
G02X487150Y368051I511J-1412D01*
G01X487118Y368061D01*
X484225Y368002D01*
X484194Y367991D01*
G02X484136Y370835I-511J1412D01*
G37*
G36*
G01X485085Y364979D02*
X485074Y364948D01*
Y362127D01*
X485084Y362096D01*
G02X482240Y362097I-1422J-483D01*
G01X482251Y362128D01*
Y364949D01*
X482241Y364980D01*
G02X485085Y364979I1422J483D01*
G37*
G36*
G01X487084Y356264D02*
X484177D01*
X484145Y356254D01*
G02Y359098I-483J1422D01*
G01X484177Y359088D01*
X487084D01*
X487116Y359098D01*
G02Y356254I483J-1422D01*
G01X487084Y356264D01*
G37*
G36*
G01Y352328D02*
X484177D01*
X484145Y352317D01*
G02Y355161I-483J1422D01*
G01X484177Y355150D01*
X487084D01*
X487116Y355161D01*
G02Y352317I483J-1422D01*
G01X487084Y352328D01*
G37*
G36*
G01X486937Y332441D02*
X486906Y332453D01*
X484094Y332615D01*
X484062Y332606D01*
G02X484225Y335446I-400J1448D01*
G01X484256Y335434D01*
X487068Y335272D01*
X487100Y335281D01*
G02X486937Y332441I400J-1448D01*
G37*
G36*
G01X487084Y328706D02*
X484177D01*
X484145Y328695D01*
G02Y331539I-483J1422D01*
G01X484177Y331528D01*
X487084D01*
X487116Y331539D01*
G02Y328695I483J-1422D01*
G01X487084Y328706D01*
G37*
G36*
G01Y324768D02*
X484177D01*
X484145Y324758D01*
G02Y327602I-483J1422D01*
G01X484177Y327592D01*
X487084D01*
X487116Y327602D01*
G02Y324758I483J-1422D01*
G01X487084Y324768D01*
G37*
G36*
G01X1123260Y727579D02*
X1120812Y727928D01*
X1120781Y727923D01*
G02X1121211Y730936I-281J1577D01*
G01X1121240Y730921D01*
X1123688Y730572D01*
X1123720Y730577D01*
G02X1123289Y727564I280J-1577D01*
G01X1123260Y727579D01*
G37*
G36*
G01X1180141Y690540D02*
X1180172Y690530D01*
X1182283Y690559D01*
X1182314Y690570D01*
G02X1182354Y687726I503J-1415D01*
G01X1182323Y687736D01*
X1180212Y687707D01*
X1180181Y687696D01*
G02X1180141Y690540I-503J1415D01*
G37*
G36*
G01X1192392Y682405D02*
X1192363Y682415D01*
X1190322Y682510D01*
X1190293Y682502D01*
G02X1190435Y685559I-403J1551D01*
G01X1190464Y685549D01*
X1192505Y685454D01*
X1192534Y685462D01*
G02X1192392Y682405I403J-1551D01*
G37*
G54D57*
X945197Y380000D03*
G54D17*
X50000Y659500D03*
X58804Y699720D03*
X109000Y844220D03*
X111000Y981500D03*
X124500Y515500D03*
X128000Y544050D03*
X121200Y584278D03*
X166200Y506500D03*
X172000Y486400D03*
X182000Y577500D03*
X176938Y680465D03*
X182500Y677500D03*
X234000Y562000D03*
X236500Y574000D03*
X238500Y705000D03*
X253500Y707250D03*
X294500Y98500D03*
X299300Y84200D03*
X313402Y156000D03*
X306155Y497700D03*
X331040Y152601D03*
X330929Y148600D03*
X317248Y156000D03*
X320338Y507683D03*
X347000Y120040D03*
X340000D03*
X338000Y127500D03*
X344055Y529000D03*
X340055Y524000D03*
X342971Y525750D03*
X339000Y878500D03*
X336000Y871500D03*
X339000Y894000D03*
Y885500D03*
X337300Y949500D03*
X357394Y131496D03*
X353740Y133300D03*
X362009Y142520D03*
Y148819D03*
Y155119D03*
X352040Y143000D03*
X349829Y153400D03*
X362036Y170876D03*
X362034Y161406D03*
X355084Y172441D03*
X351929Y162200D03*
X355040Y180000D03*
X362017Y183492D03*
X362036Y177155D03*
X358858Y177128D03*
X358848Y174010D03*
X358879Y192929D03*
X351320Y194520D03*
X361987Y189747D03*
X358850Y196050D03*
X355090Y195660D03*
X355139Y190099D03*
X351731Y190274D03*
X362500Y286000D03*
X361155Y496203D03*
X356555Y513000D03*
X357055Y507000D03*
X356055Y502000D03*
X368307Y133071D03*
X374606Y136221D03*
X368296Y136246D03*
X371456Y136221D03*
X368305Y139401D03*
X374600Y139390D03*
X377750Y139400D03*
X371458Y142520D03*
X377765Y155146D03*
X374589Y155110D03*
X371455Y148854D03*
X377787Y148812D03*
X368333Y155107D03*
X365140Y155100D03*
X377757Y145670D03*
X368333Y148827D03*
X368329Y151956D03*
X371493Y145667D03*
X368314Y142505D03*
Y145680D03*
X371457Y155080D03*
X374607Y142520D03*
X377757D03*
X365186Y170876D03*
X377732Y167703D03*
X377718Y161417D03*
X371470Y167741D03*
X371489Y161411D03*
X368309Y170830D03*
X368334Y167706D03*
X365158Y164554D03*
X368325Y164585D03*
X368326Y161400D03*
X368271Y158268D03*
X374582Y161404D03*
X365186Y177175D03*
X368320Y183460D03*
X377741Y177188D03*
X377731Y180302D03*
X371457Y173978D03*
X365187Y186605D03*
X368308Y177202D03*
X374560Y177210D03*
X371485Y177175D03*
X368307Y205511D03*
Y199211D03*
X368336Y192904D03*
X374606Y189763D03*
Y192912D03*
X377756Y211810D03*
X365158D03*
X371457D03*
X367665Y363430D03*
X368055Y380500D03*
X368555Y385000D03*
Y376500D03*
Y389000D03*
X368165Y393402D03*
X370500Y518000D03*
X379500Y963500D03*
X390354Y136221D03*
X380906Y136220D03*
X390355Y139371D03*
X380920Y139370D03*
X387173Y139376D03*
X396683Y139362D03*
X393510Y139340D03*
X384019Y139371D03*
X384055Y155117D03*
X396653D03*
X380907Y142520D03*
X387206Y145670D03*
X390355Y142520D03*
X393505Y145670D03*
X384093Y151968D03*
X393519Y151990D03*
X384056Y145670D03*
X390355D03*
X396655D03*
X387206Y142520D03*
X384056D03*
X396655D03*
X393505D03*
X384055Y158266D03*
X396653D03*
X390354Y167715D03*
X396653D03*
X384032Y167703D03*
X380944Y161417D03*
X387219Y158290D03*
X387205Y167715D03*
X384041Y170888D03*
X390392Y186614D03*
X384055Y186613D03*
X396654Y186614D03*
X396653Y174015D03*
Y180314D03*
X387204Y177164D03*
X384032Y174003D03*
X384030Y177120D03*
X396653Y199211D03*
X384055Y192912D03*
Y196062D03*
X396653Y192912D03*
X384036Y189747D03*
X384055Y211810D03*
X393504Y218109D03*
X395500Y237000D03*
X389500Y319150D03*
X392589Y317729D03*
X394055Y335000D03*
X391325Y324520D03*
X386755Y326100D03*
X384160Y328812D03*
X391555Y338350D03*
X393061Y346800D03*
X393755Y350500D03*
X390230Y349327D03*
X396055Y338000D03*
X395855Y366890D03*
X392991Y365797D03*
X391628Y358852D03*
X394915Y359725D03*
X387515Y365500D03*
X387265Y384370D03*
X394935Y385150D03*
X382803Y385207D03*
X391215Y384900D03*
X396490Y388597D03*
X388500Y400575D03*
X390543Y391950D03*
X387000Y404275D03*
X388750Y951750D03*
X387061Y986061D03*
X389500Y992000D03*
X402950Y133050D03*
X399835Y139375D03*
X412429Y136210D03*
X399783Y136237D03*
X402953Y139370D03*
X406103Y139371D03*
X412415Y148794D03*
X399779Y142531D03*
X399804Y145670D03*
X412403Y142520D03*
X406102Y155117D03*
X412402Y155118D03*
X412401Y151967D03*
X399819Y151950D03*
X406125Y148804D03*
X406110Y145660D03*
X402954Y145670D03*
Y142520D03*
X406103D03*
X402952Y167715D03*
X409251D03*
X412401Y158267D03*
X406102D03*
X402977Y174003D03*
X402952Y186613D03*
X409251D03*
X409288Y180315D03*
X402952Y180314D03*
X409251Y174015D03*
X402952Y192912D03*
X409251D03*
X399803Y211810D03*
X406102D03*
X406099Y214950D03*
X409249Y214965D03*
X412767Y233162D03*
X400000Y237500D03*
X409500Y271500D03*
X404920Y330117D03*
X412794D03*
X404920Y334054D03*
X412794D03*
X408857D03*
X400983D03*
X397983Y333998D03*
X408857Y330117D03*
X400523Y325283D03*
X412794Y341928D03*
X397555Y345146D03*
X398055Y350296D03*
X398555Y339283D03*
X408857Y345865D03*
X404965Y342120D03*
X412794Y337991D03*
X400055Y343146D03*
X412794Y365550D03*
Y357676D03*
X397117Y364138D03*
X412794Y353739D03*
X404920Y369487D03*
X412794Y361613D03*
X408925Y361680D03*
X400395Y362450D03*
X400885Y354120D03*
X404935Y353840D03*
X412794Y369487D03*
X408857D03*
Y353739D03*
X412794Y377363D03*
Y385237D03*
Y381300D03*
X399923Y372000D03*
X412794Y400985D03*
Y393111D03*
X408857Y389174D03*
X400983Y400985D03*
X404920Y397048D03*
Y400985D03*
Y389174D03*
X412794Y397048D03*
Y389174D03*
X408857Y397048D03*
X400983D03*
X404920Y393111D03*
X412794Y416733D03*
Y408859D03*
X400983Y404922D03*
X412794Y412796D03*
X404920Y404922D03*
X408857D03*
Y412796D03*
X412794Y404922D03*
X404920Y416733D03*
X400983D03*
X412794Y424607D03*
X408857Y420670D03*
X412794D03*
X404555Y430500D03*
X404920Y420670D03*
X406555Y428300D03*
X399555Y438500D03*
X428375Y119735D03*
X418940Y125000D03*
X415552Y136221D03*
X421590Y128500D03*
X418702Y136221D03*
X425000Y136220D03*
X428116Y136218D03*
X421851Y136221D03*
X423686Y126215D03*
X415549Y151990D03*
X418702Y142520D03*
X425001D03*
X421851D03*
X415552D03*
X428151D03*
X418700Y148818D03*
X428149D03*
X415551D03*
X424999D03*
X421850D03*
X428149Y164565D03*
Y170865D03*
X421876Y167705D03*
X415575Y167703D03*
X424999Y161416D03*
X428149D03*
Y183463D03*
Y177164D03*
X421876Y174005D03*
Y180304D03*
Y186603D03*
X415551Y186614D03*
X415587Y180315D03*
X415551Y174015D03*
X424999Y199211D03*
X428149D03*
X421876Y192902D03*
X428149Y192912D03*
X415551D03*
X424999D03*
X428150Y211810D03*
X415551D03*
X421850D03*
X428172Y221320D03*
X424979Y218127D03*
X428047Y218049D03*
X415551Y218109D03*
X418729Y218100D03*
X421850Y218109D03*
X418729Y221268D03*
X420500Y234500D03*
X422630Y227232D03*
X426147Y230982D03*
X420714Y225190D03*
X429444Y230192D03*
X419000Y227405D03*
X427965Y318293D03*
X419913Y318051D03*
X417650Y316400D03*
X416482Y319022D03*
X424555Y318000D03*
X420668Y330117D03*
X428542D03*
X420668Y334054D03*
X428542D03*
X424023Y320783D03*
X424605Y334054D03*
Y330117D03*
X416731D03*
X416950Y321783D03*
X416731Y334054D03*
X420668Y337991D03*
X428542Y345865D03*
X416615Y349930D03*
X428542Y349802D03*
Y341928D03*
X424605Y337991D03*
X428542D03*
X420668Y341928D03*
X424605Y349802D03*
X420668D03*
X416731Y337991D03*
X420668Y345865D03*
X416731Y341928D03*
X424605D03*
X428542Y361613D03*
Y369487D03*
Y353739D03*
X416731D03*
X420668Y357676D03*
X428542Y365550D03*
X416731Y369487D03*
X420668Y353739D03*
X416731Y365550D03*
X424605D03*
X420668D03*
X416731Y361613D03*
X420668Y369487D03*
X424605Y357676D03*
X420668Y361613D03*
X416555Y357500D03*
X428542Y357676D03*
Y385237D03*
Y381300D03*
X428500Y377000D03*
X416731Y381300D03*
Y377363D03*
X428445Y373550D03*
X420668Y377363D03*
Y385237D03*
X416731D03*
X424605Y381300D03*
X420668D03*
X428542Y400985D03*
X424605D03*
X416731Y389174D03*
X428555Y393000D03*
X420668Y389174D03*
X416731Y393111D03*
Y397048D03*
X420668Y393111D03*
X424605Y397048D03*
X428542Y389174D03*
X420668Y397048D03*
X416731Y400985D03*
X424605Y389174D03*
Y404922D03*
Y408859D03*
X420668Y404922D03*
X428542Y408859D03*
X420668D03*
X428542Y404922D03*
X428523Y416683D03*
X416731Y412796D03*
X423555Y431500D03*
X432540Y123000D03*
X435640D03*
X437599Y136221D03*
X434450D03*
X439540Y124500D03*
X431407Y136285D03*
X440931Y129061D03*
X431348Y125911D03*
X442323Y126000D03*
X437945Y127159D03*
X434449Y155118D03*
X431300Y142520D03*
X437599D03*
X437598Y148818D03*
Y155118D03*
X434450Y142520D03*
X440765Y145670D03*
X443928Y148811D03*
X443891Y151999D03*
X443890Y142565D03*
X443909Y145650D03*
X443936Y155118D03*
X431299Y164565D03*
Y170865D03*
X434449Y167716D03*
Y161417D03*
X431299Y161416D03*
X437598Y167716D03*
Y161417D03*
X443899Y161430D03*
X443882Y167737D03*
X443899Y164530D03*
X443871Y158278D03*
X431299Y183463D03*
X434449Y180314D03*
Y174015D03*
X431299Y177164D03*
X434448Y186613D03*
X431299D03*
X437598Y174015D03*
Y180314D03*
Y186614D03*
X443910Y174041D03*
X443879Y180320D03*
X443887Y177138D03*
X440769Y183480D03*
X443919D03*
X434449Y199212D03*
Y192913D03*
X437598Y205511D03*
Y199212D03*
Y192913D03*
X443897Y205512D03*
Y192914D03*
X443898Y199212D03*
X443897Y202363D03*
Y196063D03*
X437598Y211810D03*
X443897Y211811D03*
Y208662D03*
X431336Y218111D03*
X434448Y218109D03*
X437598D03*
X436529Y229500D03*
X434334Y226789D03*
X443113Y226339D03*
X439980Y232126D03*
X441379Y229700D03*
X432307Y224857D03*
X437112Y232239D03*
X445892Y225995D03*
X438500Y250000D03*
X431023Y317283D03*
X430513Y320841D03*
X436416Y330117D03*
X444290D03*
X440353D03*
X434448Y320783D03*
X440353Y334054D03*
X432523Y330283D03*
X444555Y334000D03*
X441335Y321000D03*
X436416Y334054D03*
X440353Y349802D03*
X444290D03*
X440353Y341928D03*
X436416Y345865D03*
X432585Y345850D03*
X444290Y341928D03*
X432365Y341880D03*
X444290Y337991D03*
X432605Y337880D03*
X444290Y345865D03*
X440353D03*
X440555Y338000D03*
X444290Y369487D03*
X436416D03*
X440353Y357676D03*
X444290Y353739D03*
X440353Y365550D03*
X436416Y353739D03*
Y361613D03*
X432479Y381300D03*
X444290D03*
X440353Y377363D03*
X436416Y381300D03*
X440353Y400985D03*
X432479D03*
X444290Y397048D03*
X440353D03*
X436416D03*
X444290Y389174D03*
X436416D03*
X432479Y408859D03*
Y404922D03*
X436416D03*
Y408859D03*
X444290Y404922D03*
Y408859D03*
X440353D03*
Y404922D03*
X444323Y416883D03*
X436523Y416683D03*
X442535Y426770D03*
X434723Y426283D03*
X448669Y126510D03*
X450209Y129230D03*
X447389Y129580D03*
X454676Y137495D03*
X456429Y135000D03*
X457929Y132500D03*
X451679Y148250D03*
X461685Y150386D03*
X455731Y154302D03*
X460300Y141100D03*
X454929Y146500D03*
X453929Y140334D03*
X459069Y151980D03*
X451329Y165570D03*
X453599Y156693D03*
X450196Y189764D03*
X454329Y199800D03*
X452929Y203900D03*
X452329Y194300D03*
X447063Y199234D03*
X447047Y189764D03*
X451292Y197637D03*
X456479Y202400D03*
X455929Y192800D03*
X456229Y196700D03*
X453829Y215600D03*
X453729Y219300D03*
X452393Y210236D03*
X458029Y213469D03*
X457798Y217769D03*
X457729Y206800D03*
X448840Y225775D03*
X455429Y227500D03*
X451929Y229800D03*
X456929Y224507D03*
X456103Y330117D03*
X460040D03*
X448227D03*
X452223Y333983D03*
X448227Y334054D03*
X460040D03*
X456103D03*
X460040Y341928D03*
X448227Y349802D03*
Y341928D03*
X456103D03*
X460040Y337991D03*
X455825Y349840D03*
X456055Y338000D03*
X452055D03*
X452165Y349470D03*
X456103Y369487D03*
Y353739D03*
Y361613D03*
X460040Y357676D03*
Y365550D03*
X448227D03*
Y357676D03*
X460040Y385237D03*
X456103Y381300D03*
X460040Y377363D03*
X448227Y385237D03*
Y377363D03*
X456103Y400985D03*
X460040D03*
X448227D03*
X456103Y397048D03*
X448227D03*
X456103Y389174D03*
X456223Y404883D03*
Y408783D03*
X456103Y412796D03*
X460023Y408883D03*
X452223Y404883D03*
X448227Y408859D03*
X452223Y408783D03*
X448227Y404922D03*
X450725Y425460D03*
X471480Y105660D03*
X466464Y151000D03*
X466500Y144500D03*
X463969Y147610D03*
X469429Y172500D03*
Y165590D03*
X473131Y169131D03*
X477429Y162500D03*
X469429Y179500D03*
X464570Y215750D03*
X467300Y320100D03*
X467914Y330117D03*
X463977Y334054D03*
X467914D03*
X475788Y330117D03*
Y349802D03*
Y341928D03*
X463977D03*
X471851Y337991D03*
X467914D03*
X463977D03*
X471851Y349802D03*
X467914Y345865D03*
X475788Y369487D03*
Y361613D03*
Y357676D03*
X471851Y361613D03*
Y369487D03*
Y353739D03*
Y357676D03*
X463977Y369487D03*
Y361613D03*
X475788Y381300D03*
Y377363D03*
X471851D03*
Y381300D03*
X463977D03*
X475788Y400985D03*
Y397048D03*
Y393111D03*
X471851D03*
Y397048D03*
X475788Y389174D03*
X467914Y400985D03*
Y397048D03*
Y393111D03*
Y389174D03*
X463977Y397048D03*
Y389174D03*
Y408859D03*
Y404922D03*
X467914Y408859D03*
Y404922D03*
X471851Y412796D03*
X475788Y424607D03*
X480500Y181800D03*
X483955Y318600D03*
X491536Y334054D03*
X479725Y330117D03*
X479655Y322500D03*
X487500Y333833D03*
X483662Y334054D03*
X487599Y330117D03*
X483662Y326180D03*
X484000Y322000D03*
X487599Y326180D03*
X487155Y321900D03*
X483662Y330117D03*
X491536Y341928D03*
X479725Y337991D03*
X487599D03*
X483662D03*
Y341928D03*
X487599D03*
X483662Y345865D03*
X487599Y349802D03*
X483662D03*
X487599Y345865D03*
X487603Y369483D03*
X483662Y357676D03*
X487599D03*
X483663Y365463D03*
X483662Y361613D03*
Y353739D03*
X487599D03*
X483683Y369403D03*
X479725Y369487D03*
Y361613D03*
X487643Y361523D03*
X491500Y353500D03*
X491536Y385237D03*
Y377363D03*
X479725Y381300D03*
X491536Y400985D03*
Y393111D03*
X479725Y397048D03*
Y389174D03*
X491536Y416733D03*
Y408859D03*
X487599Y416733D03*
X483662Y408859D03*
X487599Y404922D03*
X479725Y412796D03*
X491536Y420670D03*
Y424607D03*
X483662D03*
X487599D03*
X505523Y332086D03*
X499410Y322243D03*
X511500Y348000D03*
X511455Y338700D03*
X505523Y363582D03*
X507955Y356100D03*
X505523Y371456D03*
X503347Y381300D03*
Y397048D03*
Y389174D03*
X499410Y416733D03*
Y412796D03*
Y408859D03*
X503347D03*
Y404922D03*
X495473Y416733D03*
Y412796D03*
Y408859D03*
X499410Y420670D03*
Y424607D03*
X503347Y420670D03*
X495473Y424607D03*
Y420670D03*
X521700Y114000D03*
X519500Y365500D03*
X533441Y211775D03*
X559750Y264500D03*
X605000Y209500D03*
X604500Y227500D03*
Y223000D03*
X599000Y804000D03*
X622500Y696500D03*
X625000Y706000D03*
X632500Y530000D03*
X691400Y231100D03*
X710100Y182700D03*
X780000Y250000D03*
X862500Y65000D03*
X865000Y488500D03*
X874000Y56000D03*
X873500Y61500D03*
X884500Y323500D03*
X881000Y736500D03*
X945000Y141500D03*
X947500Y153000D03*
X959900Y180700D03*
X974500Y188500D03*
X975007Y194300D03*
X1002500Y653000D03*
X1001100Y776500D03*
X1015000Y477500D03*
X1011500Y667500D03*
X1022000Y492500D03*
X1022500Y637500D03*
X1027504Y853366D03*
X1045000Y266600D03*
X1055000Y214500D03*
X1055500Y360000D03*
X1062940Y629945D03*
X1054080Y680630D03*
X1084500Y223500D03*
X1088000Y461000D03*
X1088400Y647484D03*
X1103300Y492000D03*
X1113500Y614250D03*
X1113000Y630500D03*
X1105000D03*
X1114500Y645000D03*
X1118630Y714820D03*
X1110790Y738850D03*
X1116550Y783600D03*
X1119060Y791083D03*
X1132500Y333000D03*
X1132423Y663902D03*
X1135553Y663957D03*
X1132440Y676555D03*
X1129272Y673350D03*
X1129271Y670275D03*
X1126102Y676518D03*
X1122985Y670262D03*
X1122938Y676540D03*
X1132402Y673405D03*
X1132398Y667102D03*
X1129290Y676555D03*
X1126121Y679722D03*
X1132421Y679648D03*
X1132395Y670225D03*
X1126117Y685952D03*
X1129273Y689170D03*
X1126122Y689171D03*
X1129290Y692303D03*
X1126116Y692279D03*
X1132423Y695469D03*
X1132440Y692265D03*
Y686004D03*
X1132434Y682860D03*
X1129278Y682804D03*
X1119265Y683864D03*
X1135551Y685967D03*
X1129289Y686005D03*
X1126157Y695435D03*
X1129238Y704878D03*
X1132440Y701714D03*
X1129270D03*
X1126121Y711218D03*
X1129285Y708056D03*
X1126114Y701703D03*
X1126093Y704874D03*
X1132406Y704904D03*
X1132440Y698564D03*
X1129290D03*
X1126155Y708029D03*
X1129260Y714350D03*
X1135570Y711218D03*
X1126121Y714368D03*
X1132417Y711189D03*
X1129277Y711210D03*
X1128959Y729952D03*
X1126969Y727981D03*
X1132398Y720624D03*
X1132459Y717481D03*
X1127183Y740805D03*
X1126671Y744629D03*
X1126885Y736721D03*
X1123393Y743726D03*
X1124497Y734140D03*
X1124326Y738960D03*
X1126955Y731909D03*
X1124978Y747578D03*
X1130900Y766700D03*
X1124460Y768140D03*
X1125900Y764200D03*
X1129501Y776929D03*
X1120400Y781600D03*
X1126360Y792640D03*
X1127160Y788837D03*
X1129497Y792673D03*
X1130610Y788820D03*
X1134145Y788450D03*
X1132684Y792636D03*
X1124360Y788390D03*
X1132600Y784822D03*
X1120529Y786350D03*
X1123254Y792663D03*
X1131095Y799965D03*
X1124796Y800150D03*
X1144425Y325500D03*
X1143000Y629000D03*
X1138757Y663937D03*
X1151337Y660807D03*
X1151354Y663936D03*
X1148150Y663956D03*
X1141900Y663944D03*
X1148188Y667106D03*
Y670256D03*
X1151282Y667088D03*
X1141600Y673590D03*
X1141868Y680064D03*
X1151337Y670256D03*
X1141954Y676581D03*
X1135589Y673368D03*
X1144983Y667085D03*
X1145020Y670200D03*
X1136150Y676500D03*
X1135685Y679613D03*
X1135598Y667080D03*
X1135595Y670225D03*
X1141868Y670273D03*
X1138708Y667113D03*
X1139245Y675106D03*
X1151300Y682854D03*
Y692303D03*
Y689153D03*
Y686004D03*
Y695452D03*
X1148150D03*
Y692303D03*
Y689153D03*
Y686004D03*
Y682854D03*
X1139858Y692074D03*
X1139000Y685667D03*
X1144880Y707720D03*
X1145000Y711200D03*
X1138729Y714360D03*
X1151307Y714306D03*
X1141765Y711030D03*
X1145053Y714327D03*
X1148169Y711219D03*
X1141840Y714339D03*
X1138320Y710066D03*
X1151300Y698602D03*
X1148150D03*
X1135589Y701714D03*
X1151352Y711178D03*
X1140710Y707750D03*
X1138400Y705300D03*
X1136304Y707482D03*
X1151318Y717518D03*
X1148135Y720634D03*
X1138685Y720633D03*
X1141870Y717518D03*
X1148167Y717517D03*
X1138730Y717480D03*
X1141904Y720633D03*
X1150734Y736950D03*
X1149470Y734451D03*
X1137030Y745300D03*
X1146370Y769310D03*
X1142095Y773774D03*
X1151564Y776924D03*
X1146200Y766300D03*
X1142323Y780250D03*
X1138961Y776940D03*
X1150310Y783840D03*
X1142120Y795830D03*
X1145270D03*
X1138970D03*
X1145270Y792670D03*
X1141700Y785113D03*
X1138545Y787952D03*
X1145740Y789140D03*
X1138931Y792658D03*
X1142086Y789513D03*
X1136236Y782142D03*
X1151590Y792660D03*
X1143470Y782805D03*
X1141100Y831600D03*
X1159100Y640800D03*
X1157599Y663956D03*
X1167098Y663932D03*
X1160748Y660807D03*
Y657657D03*
X1160741Y663949D03*
X1163946Y663946D03*
X1157613Y673418D03*
X1167692Y674996D03*
X1154218Y679964D03*
X1154496Y667096D03*
X1163917Y670275D03*
X1160741Y667099D03*
X1163914Y673352D03*
X1167034Y667092D03*
X1157655Y667087D03*
X1160770Y673421D03*
X1163944Y667076D03*
X1154487Y670256D03*
X1160748Y682854D03*
X1157599Y686004D03*
X1154449D03*
Y682854D03*
Y689153D03*
X1160748Y695452D03*
X1157599D03*
Y692303D03*
X1154449Y695452D03*
Y692303D03*
X1163898Y695452D03*
X1160748Y692303D03*
X1163898D03*
X1157599Y689153D03*
X1160748D03*
X1163898D03*
X1160748Y686004D03*
X1163898D03*
X1157670Y707960D03*
X1167048Y714312D03*
X1154434Y714335D03*
X1157581Y714331D03*
X1163905Y711206D03*
X1157636Y711200D03*
X1163898Y698602D03*
X1160748D03*
X1157599D03*
X1154449D03*
X1167103Y711107D03*
X1167000Y727500D03*
X1157637Y717463D03*
X1157643Y720642D03*
X1152248Y730404D03*
X1154430Y717481D03*
X1152400Y727600D03*
X1167049Y717501D03*
X1167048Y720612D03*
X1163898Y717462D03*
Y720612D03*
X1157112Y731702D03*
X1164200Y744500D03*
X1157000Y734500D03*
X1166100Y731500D03*
X1152023Y733299D03*
X1163830Y747899D03*
X1158100Y769700D03*
X1162450Y769190D03*
X1167002Y767508D03*
X1167326Y776936D03*
X1161051Y792660D03*
X1164196Y795814D03*
X1153219Y781303D03*
X1161545Y788844D03*
X1162693Y780865D03*
X1158092Y787715D03*
X1154712Y792690D03*
X1165492Y780957D03*
X1154200Y788900D03*
X1154700Y795790D03*
X1161022Y785693D03*
X1165063Y787500D03*
X1167410Y785530D03*
X1154800Y799000D03*
X1173332Y663938D03*
X1176506Y663916D03*
X1176525Y679676D03*
X1170181Y670240D03*
X1176503Y670218D03*
X1182803Y670234D03*
X1176534Y673368D03*
X1179653Y670234D03*
X1173309Y673406D03*
X1179662Y673421D03*
X1176534Y676555D03*
X1179667Y679655D03*
X1182831Y679666D03*
X1182815Y676573D03*
X1170192Y667100D03*
X1176526Y667092D03*
X1173403Y670237D03*
X1173349Y667099D03*
X1182785Y685977D03*
X1176520Y685970D03*
X1179663Y685959D03*
X1173392Y685974D03*
X1173389Y689121D03*
X1176482Y682840D03*
X1176529Y692276D03*
X1179685Y692292D03*
X1176496Y695415D03*
X1179664Y695466D03*
X1182796Y695415D03*
X1179678Y689111D03*
X1182817Y689155D03*
X1173384Y692265D03*
X1182813Y698619D03*
X1176496Y698564D03*
X1179671Y698565D03*
X1170248Y714330D03*
X1173350Y698590D03*
X1179703Y714331D03*
X1173347Y714350D03*
X1176503Y714342D03*
X1176515Y704845D03*
X1179676Y711207D03*
X1179660Y704850D03*
X1171200Y706170D03*
X1179660Y708050D03*
X1176515Y708045D03*
X1173015Y708329D03*
X1176515Y711144D03*
X1173262Y711119D03*
X1182802Y714356D03*
X1169282Y729708D03*
X1173400Y717480D03*
X1176499Y720609D03*
X1170199Y717501D03*
X1173348Y720613D03*
X1176489Y717469D03*
X1171500Y733725D03*
X1175000Y734870D03*
X1171108Y777368D03*
X1170950Y795960D03*
X1170911Y784912D03*
X1170718Y782118D03*
X1185965Y676573D03*
X1190500Y674207D03*
X1185945Y695415D03*
X1196000Y710500D03*
X1190000Y705500D03*
X1199500Y743500D03*
X1201250Y627000D03*
X1203500Y698520D03*
X1218040Y719850D03*
X1249773Y551500D03*
X1249000Y723250D03*
X1258562Y672438D03*
X1259000Y699500D03*
X1257500Y710500D03*
X1259500Y724000D03*
X1279600Y694800D03*
X1276000Y694000D03*
X1272700Y694900D03*
X1277000Y712500D03*
X1272500D03*
X1275000Y732000D03*
X1287962Y710490D03*
X1289500Y716500D03*
X1292500Y730478D03*
X1305000Y596500D03*
X1305217Y612412D03*
X1305435Y603918D03*
X1307150Y691500D03*
X1307000Y729100D03*
X1310500Y737500D03*
X1307000Y732500D03*
X1300491Y732991D03*
X1322900Y524600D03*
X1322400Y533100D03*
X1318000Y696500D03*
X1319000Y708000D03*
X1351900Y524600D03*
X1352400Y533600D03*
X1381415Y581195D03*
X1380925Y598315D03*
X1377996Y610847D03*
X1380925Y602035D03*
X1377996Y607382D03*
X1385135Y581195D03*
G54D13*
X8200Y857700D03*
X8000Y853500D03*
X35304Y832220D03*
X34304Y897720D03*
X47483Y387776D03*
X43883Y387769D03*
X52000Y655500D03*
X44804Y837220D03*
X44500Y851500D03*
X49000Y861500D03*
X52000Y872720D03*
X37232Y877242D03*
X51896Y878668D03*
X42554Y891720D03*
X37211Y881115D03*
X37758Y884674D03*
X40304Y887220D03*
X51304Y882220D03*
X47804Y906720D03*
X43804Y907720D03*
X41304Y927220D03*
X50270Y929186D03*
X62783Y387776D03*
X66483Y387876D03*
X56883D03*
X53183Y387676D03*
X55304Y669720D03*
X58804Y710220D03*
X68147Y722511D03*
X62704Y739620D03*
X55304Y746220D03*
X65272Y758504D03*
X64683Y762056D03*
X59272Y790504D03*
X57772Y801504D03*
X61492Y803004D03*
X55022Y826720D03*
X66022Y827254D03*
X57304Y815720D03*
X61304Y815220D03*
X65804Y835720D03*
X57804Y834720D03*
X61804D03*
X52304Y868220D03*
X60804Y907720D03*
X56804Y907220D03*
X52304Y906720D03*
X64804Y907720D03*
X52804Y943220D03*
X57770Y932686D03*
X55270Y929186D03*
X52770Y932686D03*
X62770D03*
X60270Y929186D03*
X52804Y938795D03*
X71883Y387976D03*
X76083D03*
X76804Y710220D03*
X71846Y722426D03*
X77272Y724004D03*
X75432Y735059D03*
X83849Y735513D03*
X80272Y735103D03*
X68910Y760642D03*
X83112Y760720D03*
X75432Y758844D03*
X80624Y764241D03*
X68762Y764239D03*
X82804Y794920D03*
X84804Y808720D03*
X79000Y836500D03*
X84221Y836078D03*
X77500Y832000D03*
X70909Y847325D03*
X72304Y869720D03*
X76304D03*
X81304Y884470D03*
X89804Y669720D03*
X95304Y686220D03*
X94804Y708220D03*
X99804Y709220D03*
X87772Y735059D03*
X92365Y735040D03*
X85672Y763504D03*
X86404Y774720D03*
X85304Y768720D03*
X93347Y765754D03*
X85204Y798220D03*
X92304Y835720D03*
X87928Y848107D03*
X95700Y926300D03*
X105000Y834500D03*
X113222Y831222D03*
X112500Y835000D03*
X110500Y848500D03*
X115500D03*
X109054Y892720D03*
X102304Y895220D03*
X114054Y892720D03*
X106554Y895720D03*
X116554D03*
X111554Y896220D03*
X105804Y943220D03*
X109054Y932720D03*
X116600Y929924D03*
X114054Y932470D03*
X111554Y929720D03*
X108804Y938795D03*
X115500Y983500D03*
X127654Y293453D03*
X132123Y318877D03*
X123654Y320953D03*
X131500Y324000D03*
X122906Y331953D03*
X127301Y354709D03*
X131147D03*
X132500Y547000D03*
Y559600D03*
Y556000D03*
Y551500D03*
X133500Y582500D03*
X125050Y583000D03*
X126500Y587500D03*
X121685Y587919D03*
X134000Y587000D03*
X130000Y666500D03*
X129304Y798720D03*
X122500Y845500D03*
X128000Y870500D03*
X129100Y892924D03*
X124054Y892220D03*
X121600Y895266D03*
X119054Y892720D03*
X126554Y895470D03*
X121598Y929924D03*
X131554Y929470D03*
X129054Y932720D03*
X126554Y929882D03*
X124098Y932515D03*
X119099Y932516D03*
X118000Y991500D03*
X145500Y283500D03*
X143147Y354709D03*
X139301D03*
X147500Y472100D03*
X135500Y511000D03*
X136000Y566000D03*
X136500Y576900D03*
Y573300D03*
Y580500D03*
Y569700D03*
X140500Y568000D03*
X144000Y572500D03*
X143500Y710500D03*
X141054Y795820D03*
X150225Y790412D03*
X146304Y804220D03*
X146500Y808220D03*
X165793Y294309D03*
X155874Y313961D03*
Y317807D03*
X164147Y328699D03*
X155874Y326957D03*
Y323111D03*
X155147Y354709D03*
X162801D03*
X166647D03*
X151301D03*
X160000Y465500D03*
X158500Y461500D03*
X153050Y486500D03*
X163225Y522080D03*
X154625Y550290D03*
X154755Y539310D03*
X163305Y554750D03*
X160500Y586500D03*
X156900D03*
X152948Y587000D03*
X166000Y662500D03*
X157750Y662250D03*
X166500Y650500D03*
X162500Y670000D03*
X163000Y710500D03*
X150900Y812500D03*
X154500D03*
X152500Y840000D03*
X157500Y867500D03*
X169639Y294309D03*
X179088Y294909D03*
X175242D03*
X167993Y328699D03*
X179622Y328749D03*
X175776D03*
X182800Y465800D03*
Y471300D03*
X171500Y478699D03*
X177493Y533493D03*
X170339Y537396D03*
X180555Y560500D03*
X175993Y559938D03*
X175055Y569500D03*
X167469Y588969D03*
X174000Y830500D03*
X170500Y835500D03*
X179500Y847000D03*
X172000Y868000D03*
X168400D03*
X183000Y865750D03*
X188295Y297209D03*
X193841Y297755D03*
X185039Y295209D03*
X191295D03*
X186614Y319028D03*
X190295Y318709D03*
X198864Y323297D03*
X192874Y334307D03*
Y330461D03*
X184295Y322209D03*
X192795Y321709D03*
X192874Y341611D03*
Y345457D03*
X192500Y431500D03*
X187300Y457300D03*
X191800D03*
X190800Y462800D03*
X189355Y526470D03*
X185000Y533562D03*
X185305Y521100D03*
X195725Y540750D03*
X195865Y552940D03*
X198500Y563000D03*
X189500Y573500D03*
X194500Y724000D03*
X186000Y841500D03*
X185000Y856000D03*
X185500Y848260D03*
X187000Y878000D03*
X199000Y891500D03*
X190500Y894000D03*
X195000Y891500D03*
X204285Y294909D03*
X213733D03*
X200439D03*
X209887D03*
X208338Y323297D03*
X202710D03*
X212134D03*
X212500Y435000D03*
X207773Y516562D03*
X208305Y548670D03*
Y536320D03*
Y562640D03*
X203000Y564500D03*
X201000Y625500D03*
X212500Y716500D03*
X204500Y721000D03*
X215250Y833750D03*
X205500Y830000D03*
X204000Y862000D03*
X212000Y891500D03*
X203500Y894000D03*
X208000Y892000D03*
X232500Y419000D03*
Y431000D03*
Y425000D03*
X229055Y497000D03*
X216500Y516000D03*
X228319Y524798D03*
X230000Y680500D03*
X221000Y723000D03*
X218000Y801500D03*
X223500Y825500D03*
X228000Y825000D03*
X232000D03*
X227000Y858000D03*
X217000Y858500D03*
X222000Y853500D03*
Y858500D03*
Y863500D03*
Y893600D03*
X243755Y490890D03*
X242003Y506327D03*
X234755Y509700D03*
X245205Y504679D03*
X246613Y501365D03*
X237055Y513500D03*
X234185Y527138D03*
X248855Y532300D03*
X239555Y519500D03*
X247500Y829500D03*
X237953Y861453D03*
X259055Y500500D03*
X260288Y514589D03*
X264655Y511100D03*
X250055Y510800D03*
X256055Y531016D03*
X260555Y525500D03*
X253679Y523137D03*
X260605Y519245D03*
X263555Y534500D03*
X261255Y549000D03*
X265455Y544853D03*
X252055Y548760D03*
X257555Y549000D03*
X258500Y608500D03*
Y613500D03*
X253500Y608500D03*
X253555Y613500D03*
X251000Y835500D03*
X251500Y855500D03*
X252000Y846500D03*
X252500Y851500D03*
X250362Y865000D03*
X253610Y863447D03*
X268300Y219800D03*
X279997Y514179D03*
X275555Y531500D03*
X275055Y521825D03*
X266055Y531725D03*
X272571Y541150D03*
X278367Y535140D03*
X269555Y536000D03*
X271451Y544616D03*
X278676Y539500D03*
X270000Y870000D03*
Y865500D03*
X276500Y888500D03*
X280500Y955000D03*
X278050Y958500D03*
X296200Y94400D03*
X293929Y342000D03*
X292525Y498780D03*
X292045Y504897D03*
X293273Y509500D03*
X282626Y516639D03*
X291530Y525407D03*
X283103Y520208D03*
X286588Y519305D03*
X292555Y533043D03*
X291755Y529000D03*
X286555Y524524D03*
X282555Y540700D03*
X283038Y536850D03*
X309500Y78500D03*
X313250Y85250D03*
X311500Y81500D03*
X314000Y102500D03*
X302000Y94300D03*
X299831Y144328D03*
X303677D03*
X305852Y163800D03*
X309698D03*
X299395Y449160D03*
X312925Y462560D03*
X298662Y479783D03*
X305055Y472500D03*
X302555Y476000D03*
X312773Y529878D03*
X313000Y582000D03*
X324500Y10500D03*
X327000Y89500D03*
X323000D03*
X319309Y89503D03*
X317500Y101000D03*
X324200Y101900D03*
X321500Y118500D03*
X325929Y127700D03*
X327100Y136294D03*
Y139857D03*
X326422Y152507D03*
Y148944D03*
X319800Y146898D03*
Y143052D03*
X322229Y218800D03*
X316129Y213000D03*
X328000Y285000D03*
X327000Y308000D03*
X331000Y308018D03*
X330555Y467500D03*
X325873Y477006D03*
X325854Y480606D03*
X317195Y493280D03*
X317255Y514170D03*
X330491Y525490D03*
X315725Y549790D03*
X329695Y534650D03*
X317758Y581297D03*
X329055Y569500D03*
X321780Y575000D03*
X314930Y585500D03*
X321500Y688000D03*
X333000Y90500D03*
X343000Y89000D03*
X339500Y75500D03*
X337500Y84250D03*
X342000Y102000D03*
X346000D03*
X334600Y129468D03*
Y133031D03*
X344429Y312000D03*
X341500Y309500D03*
X343929Y320700D03*
X342500Y340000D03*
X338500Y397500D03*
X336375Y452870D03*
X338985Y467405D03*
X343688Y509533D03*
X334055Y526000D03*
X347213Y546700D03*
X334555Y548500D03*
X341055Y534500D03*
X344655D03*
X345500Y556500D03*
X339888Y586388D03*
X346402Y653004D03*
X342500Y653000D03*
X335500Y868000D03*
X332129Y889371D03*
X331829Y885500D03*
X338000Y942000D03*
X339500Y960000D03*
X352000Y66000D03*
X357500Y79500D03*
Y75500D03*
X348429Y130000D03*
X353929Y128500D03*
X351429Y126500D03*
X351929Y332500D03*
X364015Y468450D03*
X349575Y479503D03*
X349815Y475550D03*
X358797Y532258D03*
X354055Y534000D03*
X352095Y524040D03*
X362555Y534500D03*
X348255D03*
X360500Y588500D03*
X350000Y652878D03*
X362210Y876200D03*
X363480Y907783D03*
X362000Y904500D03*
X363000Y931500D03*
X359000D03*
X354000Y960000D03*
X363614Y971524D03*
X361000Y974000D03*
X360024Y979100D03*
X366600Y285800D03*
X377855Y300110D03*
X374000Y293500D03*
X372055Y319500D03*
X369555Y322500D03*
X372055Y364000D03*
X370275Y413540D03*
X371710Y406535D03*
X369555Y417500D03*
X370575Y409952D03*
X375055Y444500D03*
X367022Y482783D03*
X378255Y471840D03*
X379000Y531000D03*
X371000Y866500D03*
X376041Y866041D03*
X375500Y906000D03*
Y901500D03*
X365500Y916000D03*
X369341Y916117D03*
X371100Y926000D03*
X377000Y927500D03*
X372300Y918749D03*
X369500Y936500D03*
X368000Y932000D03*
X371000Y930000D03*
X376000Y960000D03*
X364396Y980109D03*
X366878Y977500D03*
X369200Y980252D03*
X372500Y977918D03*
X377464Y987493D03*
X377250Y982250D03*
X390000Y13500D03*
X385000D03*
X388000Y233500D03*
X388149Y229780D03*
X393429Y229500D03*
X395450Y265400D03*
X390100Y263600D03*
X387500Y261000D03*
X381500Y297000D03*
X395104Y291056D03*
X382455Y331870D03*
X393055Y451000D03*
Y447400D03*
X385463Y450948D03*
X386055Y454500D03*
X388885Y471100D03*
X381500Y534000D03*
X384046Y536546D03*
X396000Y714500D03*
X392500Y718500D03*
X391000Y866500D03*
X396500Y888500D03*
X396600Y895855D03*
X396330Y899705D03*
X396500Y904000D03*
X384000Y926500D03*
X389838Y942300D03*
X388500Y955250D03*
X390000Y946500D03*
X397900Y231800D03*
X399500Y240500D03*
X401855Y293500D03*
X408656Y291500D03*
X405555Y293500D03*
X401555Y318000D03*
X406555Y320500D03*
X403255Y425950D03*
X404500Y877300D03*
X397600Y892000D03*
X399500Y901500D03*
X403250Y949000D03*
X408250Y949500D03*
X410500Y954500D03*
X405704Y952046D03*
X398250Y955000D03*
X400750Y952000D03*
X410000Y983500D03*
X410500Y987500D03*
X414000Y8000D03*
X418192Y114237D03*
X421000Y231500D03*
X424929Y264700D03*
X428100Y266500D03*
X419600Y282900D03*
X419455Y293000D03*
X416187Y294711D03*
X429500Y311000D03*
X425278Y802000D03*
X416046Y959546D03*
X414500Y948500D03*
X414215Y952089D03*
X422098Y948630D03*
X418500Y948500D03*
X413500Y957000D03*
X416000Y964000D03*
X420000D03*
X413600Y983500D03*
X438500Y9000D03*
X433929Y100000D03*
X430540Y108750D03*
X433929Y264300D03*
X439800Y284100D03*
X439200Y294550D03*
X432500Y301000D03*
X435000Y294000D03*
X444778Y802100D03*
X438278D03*
X431778Y802000D03*
X431278Y883000D03*
X444278D03*
X437778D03*
X432000Y933500D03*
X430500Y962000D03*
X459429Y106000D03*
X448929Y99500D03*
X457500Y121000D03*
X450929Y118000D03*
X457429Y171500D03*
X462500Y169000D03*
X455054Y179475D03*
X458429Y175590D03*
X456000Y243500D03*
X460000D03*
X461100Y260050D03*
X459055Y263500D03*
X458685Y425710D03*
X456278Y802100D03*
X450778Y883000D03*
X460778D03*
X471290Y118361D03*
X471429Y133500D03*
X477291Y147500D03*
X477900Y153600D03*
X471000Y141000D03*
X477929Y158000D03*
X467600Y158400D03*
X465600Y162000D03*
X475216Y182917D03*
X470000Y188500D03*
X462679Y176900D03*
X466700Y259400D03*
X464055Y256500D03*
X463371Y290371D03*
X464200Y307838D03*
X463945Y349700D03*
X466655Y425340D03*
X472055Y425000D03*
X475778Y802100D03*
X462778D03*
X469278D03*
X473778Y883000D03*
X467278D03*
X488500Y114200D03*
X481429Y150000D03*
X491257Y315952D03*
X495103D03*
X487612Y318606D03*
X492555Y431250D03*
X480278Y883000D03*
X488000Y904500D03*
X483500Y907500D03*
X499390Y153500D03*
X503500D03*
X503929Y146500D03*
X506429Y149500D03*
X495929Y164500D03*
X508500Y320000D03*
X504453Y314200D03*
X500607D03*
X495555Y369500D03*
X507355Y390800D03*
X505922Y415371D03*
X506163Y419973D03*
X508100Y605500D03*
X506000Y610000D03*
X513200Y121450D03*
X513000Y156500D03*
X512000Y320000D03*
X519706Y314000D03*
X515860D03*
X527002Y319359D03*
X523348D03*
X526500Y346532D03*
Y342969D03*
Y352969D03*
X520500Y351500D03*
Y347937D03*
Y358937D03*
X526500Y356532D03*
X520500Y362500D03*
X533000Y153800D03*
X528500Y172000D03*
X539714Y179150D03*
X542500Y188500D03*
X537479Y197875D03*
X539073Y237300D03*
X531590Y297620D03*
X534500Y295500D03*
X528500Y310000D03*
X534629Y311171D03*
X534960Y321000D03*
X538614D03*
X529848Y325500D03*
X533502D03*
X550500Y188000D03*
X560500Y186000D03*
X555500Y194000D03*
X559500D03*
X545000Y195000D03*
X549926Y204000D03*
X557275Y214918D03*
X553675Y215913D03*
X550075D03*
X559961Y209419D03*
X546916Y217641D03*
X548000Y231000D03*
X547746Y225303D03*
X559971Y237753D03*
X553555Y321000D03*
X560253Y329500D03*
X557061Y334194D03*
X553155Y334300D03*
X548000Y369500D03*
X555935Y363000D03*
X559500Y604500D03*
X572000Y189000D03*
X571398Y183602D03*
X561429Y174441D03*
X575500Y198400D03*
X576650Y204500D03*
X563100Y194000D03*
X568158Y206455D03*
X571461Y207887D03*
X569000Y217000D03*
X569127Y213100D03*
X564583Y206028D03*
X577119Y233139D03*
X564631Y234356D03*
X569322Y234220D03*
X573179Y233535D03*
X575425Y228505D03*
X563704Y272000D03*
X563555Y333000D03*
X564215Y369339D03*
X566430Y366500D03*
X569555Y364000D03*
X562555Y364500D03*
X587175Y202525D03*
X591413Y199087D03*
X583500Y204500D03*
X585325Y198000D03*
X583325Y208500D03*
X583204Y236805D03*
X580709Y232091D03*
X619876Y195000D03*
X617828Y303250D03*
X613962D03*
X623500Y576500D03*
X622500Y608500D03*
X633578Y303250D03*
X629712D03*
X642800Y433587D03*
X641500Y449500D03*
X636500Y444800D03*
X640500Y444500D03*
X635325Y457500D03*
X628524Y591976D03*
X649323Y303250D03*
X645457D03*
X652714Y428214D03*
X647500Y425500D03*
X645500Y459500D03*
X654300Y490300D03*
X674469Y99380D03*
X674358Y103170D03*
X665073Y303250D03*
X661207D03*
X669025Y441725D03*
X660500Y436538D03*
X669462Y472500D03*
X667056Y475500D03*
X673010Y474436D03*
X673300Y579000D03*
X669000D03*
X663500Y610500D03*
X674688Y696751D03*
X670474Y808700D03*
X671500Y861000D03*
X673500Y864000D03*
X672000Y967750D03*
X667000Y969700D03*
X666750Y961550D03*
X685519Y55019D03*
X676748Y52000D03*
X684861Y58584D03*
X686000Y62000D03*
X684197Y74703D03*
X687500Y440500D03*
X677500Y472500D03*
X688500Y606000D03*
X683000Y603950D03*
X677500Y612000D03*
X680000Y640000D03*
X691000Y704500D03*
X677500Y699000D03*
X682968Y758284D03*
X677500Y773500D03*
X678468Y805284D03*
X691300Y807300D03*
X679000Y865050D03*
X676500Y967750D03*
X706716Y82448D03*
X705500Y575600D03*
X702918Y782734D03*
X704000Y892500D03*
X716034Y53966D03*
X716466Y65466D03*
X711216Y82402D03*
X720216Y82138D03*
X711500Y179400D03*
X725000Y452300D03*
X720700Y564200D03*
X717036Y563783D03*
X709750Y585200D03*
X719918Y754734D03*
X715118Y776134D03*
X717468Y810784D03*
X722000Y808500D03*
X720500Y860000D03*
X710750Y863250D03*
X714000Y867500D03*
X714500Y891000D03*
X740500Y75000D03*
X728100Y213800D03*
X732500Y455500D03*
X736000Y464500D03*
X728500Y482500D03*
X730000Y536500D03*
X733500Y568500D03*
X729900D03*
X741500Y582450D03*
X737000Y583640D03*
X740768Y763984D03*
X735500Y771984D03*
X736000Y810500D03*
X733768Y800734D03*
X741050Y869500D03*
X740000Y886000D03*
X737290Y903000D03*
X733000Y969700D03*
X754500Y67500D03*
X747000Y210000D03*
X755697Y303250D03*
X751484Y540600D03*
X755000Y727500D03*
X757500Y743500D03*
X757000Y896400D03*
X749500Y974300D03*
X759563Y303250D03*
X771447D03*
X773500Y326000D03*
X758500Y457000D03*
X772024Y478976D03*
X774500Y489500D03*
X760500D03*
X766000Y635000D03*
X763000Y648000D03*
X767000Y648500D03*
X771000Y689500D03*
X760500Y707950D03*
X768000Y728000D03*
X763500Y839500D03*
X768000Y833000D03*
X766750Y849250D03*
X774500Y890500D03*
X775748Y188500D03*
X789500Y235837D03*
X787192Y303250D03*
X775313D03*
X779000Y458000D03*
X776000Y478828D03*
X788774Y482774D03*
X786500Y575688D03*
X786032Y570468D03*
X783500Y649000D03*
X784804Y673304D03*
X779500Y705000D03*
X785000Y892000D03*
X785500Y969700D03*
X796000Y167600D03*
X795500Y163408D03*
X802942Y303250D03*
X791058D03*
X806808D03*
X798000Y400500D03*
X796074Y479000D03*
X803500Y655000D03*
X798000Y706000D03*
X802000Y724000D03*
X801750Y867500D03*
X818000Y240900D03*
X821100Y348480D03*
Y352480D03*
X808500Y363500D03*
X823500Y480000D03*
X814500Y472500D03*
X823500Y556500D03*
X815900Y564000D03*
X819500D03*
X821250Y845750D03*
X810500Y851000D03*
X819000Y868500D03*
X832000Y137500D03*
X826198Y239950D03*
X833555Y262000D03*
X832500Y404000D03*
X833500Y613000D03*
X835000Y719000D03*
X826500Y743000D03*
X824560Y868560D03*
X856055Y262500D03*
X842555Y262000D03*
X854820Y352380D03*
X850540Y346070D03*
X844410Y346360D03*
X847500Y352000D03*
X852000Y401500D03*
X842000D03*
X847000Y396500D03*
Y401500D03*
Y406500D03*
X849500Y622000D03*
X846500Y710000D03*
X845500Y865000D03*
X873000Y68500D03*
X870100Y237500D03*
X869544Y226000D03*
X860400Y231000D03*
X860555Y262500D03*
X863820Y363880D03*
X868820D03*
X870500Y444000D03*
Y448000D03*
X857500Y485500D03*
X862500Y621250D03*
X859500Y629500D03*
X872000Y636000D03*
X867500Y655200D03*
X860718Y683684D03*
X877860Y316330D03*
X884120Y351630D03*
X887950Y359730D03*
X874910Y360160D03*
X879510Y355410D03*
X887940Y380200D03*
X878000Y404500D03*
X876000Y435500D03*
X886300Y443100D03*
X882700D03*
X885000Y438700D03*
X877000Y479500D03*
X876000Y631700D03*
X881000Y710000D03*
X899000Y312500D03*
X898000Y316000D03*
X903480Y324230D03*
X893500Y427000D03*
X893600Y443100D03*
X889900D03*
X903075Y472000D03*
X918420Y449130D03*
X907000Y465050D03*
X917000Y752500D03*
X923000Y51500D03*
X936000Y373500D03*
X924465Y388465D03*
X936030Y457540D03*
X937000Y489000D03*
X935400Y597300D03*
X939500Y352000D03*
X953500Y348927D03*
X944000Y434000D03*
X958500Y187500D03*
X957990Y191064D03*
X962000Y251500D03*
X965500Y260500D03*
X963500Y256000D03*
X959500Y351688D03*
X965000Y364500D03*
X964000Y354000D03*
X970382Y455872D03*
X961700Y477500D03*
X957500Y585500D03*
X961500D03*
X970750Y703000D03*
X980490Y198827D03*
X982075Y439500D03*
X973015Y453416D03*
X977000Y547500D03*
X982500Y549500D03*
X978000Y554000D03*
X975000Y701000D03*
X1003000Y59500D03*
X988900Y434800D03*
X992690Y466750D03*
X996910Y466560D03*
X994500Y491000D03*
X1003422Y490578D03*
X992000Y505500D03*
X1002500Y520000D03*
X990500Y536500D03*
X994500Y543800D03*
X998500Y591500D03*
X989000Y659500D03*
Y757150D03*
X1016500Y87500D03*
X1020500Y124500D03*
Y142000D03*
X1014000Y487000D03*
X1007500Y507000D03*
X1008500Y533400D03*
X1016500Y519500D03*
X1008500Y543700D03*
X1013500Y559000D03*
X1016900Y561000D03*
X1017982Y585018D03*
X1007532Y902468D03*
X1033500Y118000D03*
X1025500Y129500D03*
X1033500Y124000D03*
X1037085Y137000D03*
X1023000Y155000D03*
X1028000Y164500D03*
X1023600Y173000D03*
X1031524Y218476D03*
X1033900Y225500D03*
X1027426Y346500D03*
X1023000Y347000D03*
X1031000Y348500D03*
Y355950D03*
X1030000Y403500D03*
X1036500Y581500D03*
X1035000Y594500D03*
X1021000Y588500D03*
X1025500Y657000D03*
X1023500Y727000D03*
X1037000Y734000D03*
X1024387Y738230D03*
X1035000Y800000D03*
Y804500D03*
X1032657Y901500D03*
X1027716Y914784D03*
X1032200Y921500D03*
X1045031Y138031D03*
X1041485Y137409D03*
X1040000Y182000D03*
X1052500Y187500D03*
X1037500Y225500D03*
X1040000Y579000D03*
X1038000Y604000D03*
X1053500Y620500D03*
X1046000Y644000D03*
X1038000Y635000D03*
X1042450Y648500D03*
X1045500Y639500D03*
X1050092Y655052D03*
X1052500Y693000D03*
X1052678Y704084D03*
X1038500Y706500D03*
X1052500Y709000D03*
Y700000D03*
X1052648Y712724D03*
X1040208Y745020D03*
X1052500Y773350D03*
X1044000Y763940D03*
X1064000Y80000D03*
X1055500D03*
X1059500D03*
X1068000D03*
Y76000D03*
X1064000D03*
X1059500D03*
X1055500D03*
X1068500Y118500D03*
X1069000Y124500D03*
X1060900Y173534D03*
X1056500Y194000D03*
X1061000Y211500D03*
X1055000Y219284D03*
X1060766Y395426D03*
X1061200Y399000D03*
X1068300Y488700D03*
X1059000Y558190D03*
X1058000Y599500D03*
X1056000Y604000D03*
X1058500Y660900D03*
X1054900D03*
X1070000Y650725D03*
X1058350Y681450D03*
X1068500Y677000D03*
X1054500Y697000D03*
X1068500Y687000D03*
X1066000Y717000D03*
X1059800Y719740D03*
X1054000Y735000D03*
X1056350Y748000D03*
X1063000Y780000D03*
X1072000Y136000D03*
X1080300Y191000D03*
X1084500Y202500D03*
X1078500Y464000D03*
X1080000Y520000D03*
X1081000Y548000D03*
Y544400D03*
X1084599Y544520D03*
X1086000Y556000D03*
X1071500Y589000D03*
X1074500Y627500D03*
X1073000Y637500D03*
X1085000Y661000D03*
X1084300Y741874D03*
X1071500Y739000D03*
X1084000Y748099D03*
X1070098Y764500D03*
X1083700Y835725D03*
X1077000Y943075D03*
X1083200Y956500D03*
X1093894Y126500D03*
X1090028D03*
X1092500Y461500D03*
X1098500Y465000D03*
X1089000Y508500D03*
X1100575Y559075D03*
X1098000Y562000D03*
X1091425Y551425D03*
X1093500Y640000D03*
X1094500Y657500D03*
X1091000Y692519D03*
X1090257Y724253D03*
X1087600Y727029D03*
X1094853Y726853D03*
X1095500Y812000D03*
X1097500Y849000D03*
X1089000Y867284D03*
X1099623Y869123D03*
X1097423Y906546D03*
X1093500Y905500D03*
X1110318Y275600D03*
X1111500Y517500D03*
X1107500Y580000D03*
X1114883Y591925D03*
X1106000Y609500D03*
Y605500D03*
X1107000Y763000D03*
X1110300Y790000D03*
X1111834Y813334D03*
X1113500Y824500D03*
X1111000Y836000D03*
X1107160Y843160D03*
X1128000Y288500D03*
X1132300Y288800D03*
X1130000Y361500D03*
X1124327Y465391D03*
X1123500Y521500D03*
X1128149Y525261D03*
X1130928Y527550D03*
X1132000Y562000D03*
X1125600Y570600D03*
X1135000Y597000D03*
X1132222Y593278D03*
X1119487Y588088D03*
X1122353Y590268D03*
X1125000Y603050D03*
X1126000Y618000D03*
Y627329D03*
X1131000Y631000D03*
X1121500Y621600D03*
X1130490Y627436D03*
X1125041Y631000D03*
X1120500Y729500D03*
X1124000Y729000D03*
X1128430Y749640D03*
X1126642Y785505D03*
X1123200Y783900D03*
X1130030Y820000D03*
X1146500Y267000D03*
X1146000Y258500D03*
X1151000Y264500D03*
X1146500Y275500D03*
X1136100Y288900D03*
X1136450Y294650D03*
X1150640Y359860D03*
X1146640D03*
X1142640D03*
X1151500Y522000D03*
X1143500Y542000D03*
X1147500D03*
X1136075Y559075D03*
X1145900Y579800D03*
X1136500Y592500D03*
X1139632Y594441D03*
X1140500Y589000D03*
X1141100Y585400D03*
X1147000Y619000D03*
X1147400Y729900D03*
X1153700Y267700D03*
X1156100Y316405D03*
Y312795D03*
X1165000Y308175D03*
Y304565D03*
X1161530Y360430D03*
X1157480Y361620D03*
X1157700Y368500D03*
X1160058Y364558D03*
X1155400Y371500D03*
X1164000Y397000D03*
X1168000Y390250D03*
X1166500Y415500D03*
X1155500Y450758D03*
Y446892D03*
X1161000Y541500D03*
X1155000Y594500D03*
X1165476Y613393D03*
X1152500Y608500D03*
X1165672Y609672D03*
X1164500Y628723D03*
X1159075Y630600D03*
X1154847Y630908D03*
X1156377Y627623D03*
X1153500Y784190D03*
X1164500Y857500D03*
X1162000Y960625D03*
X1181427Y251500D03*
X1180677Y256500D03*
X1173777Y290125D03*
X1169777D03*
X1173125Y323716D03*
X1169515D03*
X1184000Y351500D03*
X1174500Y366000D03*
X1182000Y357000D03*
X1174400Y356500D03*
X1178000D03*
X1175125Y370000D03*
X1174500Y404000D03*
X1173500Y422500D03*
Y554000D03*
X1181350Y595450D03*
X1169075Y613500D03*
X1183000Y628000D03*
X1177100Y624750D03*
X1178500Y653100D03*
X1184500Y749500D03*
Y772782D03*
X1173200Y789500D03*
X1177000Y860000D03*
X1169000Y856000D03*
X1181500Y949000D03*
X1188000Y248500D03*
X1192743Y289800D03*
X1188877D03*
X1199685Y344588D03*
X1196075D03*
X1189000Y421500D03*
X1195000Y428000D03*
X1197675Y533125D03*
X1191000Y528000D03*
X1189000Y533825D03*
X1194564Y530936D03*
X1185500Y548075D03*
X1200500Y547925D03*
X1186000Y615500D03*
X1196000Y605800D03*
X1184956Y619272D03*
X1191000Y663000D03*
X1193804Y657175D03*
X1191000Y667000D03*
X1197500Y665500D03*
X1199551Y683968D03*
X1195937Y683849D03*
X1189890Y684053D03*
X1192937Y683911D03*
X1196500Y745500D03*
Y736687D03*
X1192500Y745500D03*
X1192038Y761481D03*
X1188500Y773000D03*
X1184975Y767500D03*
X1194000Y764500D03*
X1190000Y767500D03*
X1196000Y847500D03*
Y874500D03*
X1207500Y239500D03*
X1210800Y379700D03*
X1216000Y390000D03*
X1209500Y404500D03*
X1216500Y439500D03*
X1212500Y436000D03*
X1217000Y452500D03*
X1210000Y507500D03*
X1209500Y514000D03*
X1213100D03*
X1214450Y509000D03*
X1206400Y536800D03*
X1210000D03*
X1201500Y535000D03*
X1205240Y568760D03*
X1215500Y605300D03*
X1207700Y605500D03*
X1208500Y623000D03*
X1204500Y659500D03*
X1203181Y683968D03*
X1206781Y684003D03*
X1216000Y702500D03*
X1210500Y733500D03*
X1206500Y757000D03*
X1213500Y756000D03*
X1202218Y811282D03*
X1211000Y847500D03*
X1208940Y874560D03*
X1227500Y500500D03*
Y504246D03*
X1220500Y513000D03*
X1229500Y533000D03*
X1231632Y537000D03*
X1221500Y539500D03*
X1233000Y554502D03*
X1219200Y564600D03*
X1231450Y677500D03*
X1225500Y714500D03*
X1229000Y716000D03*
Y719600D03*
Y740000D03*
X1230219Y747469D03*
X1232000Y738000D03*
X1234000Y747500D03*
X1224500Y757500D03*
X1228547Y772547D03*
Y778453D03*
X1231000Y768500D03*
X1221000Y764750D03*
X1233000Y782500D03*
X1223500Y798500D03*
X1223000Y826500D03*
X1218500Y834500D03*
X1229807Y847000D03*
X1239000Y190500D03*
X1240000Y209449D03*
X1243000Y431500D03*
X1250000Y422000D03*
X1234500Y439000D03*
X1248250Y439250D03*
X1250450Y462000D03*
X1242000Y459000D03*
X1247800Y472750D03*
X1246750Y476250D03*
X1249000Y509500D03*
X1249251Y528688D03*
X1235482Y546982D03*
X1240000Y546500D03*
Y542900D03*
X1240173Y550327D03*
X1250500Y567000D03*
X1241000Y631500D03*
X1237500Y675500D03*
X1239500Y671000D03*
X1235000Y682000D03*
X1244371Y733129D03*
X1236500Y737925D03*
X1243000Y743000D03*
X1241000Y734500D03*
X1240016Y761500D03*
X1238000Y764500D03*
X1249500Y765500D03*
X1248950Y769500D03*
X1238047Y791953D03*
X1240045Y788957D03*
X1241984Y796000D03*
X1243953Y789000D03*
X1240660Y829000D03*
X1235258Y820758D03*
X1257000Y33000D03*
X1260677Y237000D03*
X1264177Y233500D03*
X1256000Y252000D03*
X1262558Y254942D03*
X1261677Y241500D03*
Y245500D03*
X1264500Y260000D03*
X1254944Y268567D03*
X1263000Y278500D03*
X1250677Y287500D03*
Y283500D03*
X1254944Y272433D03*
X1260577Y299968D03*
Y296102D03*
X1253477Y312800D03*
X1253577Y308800D03*
X1253177Y320500D03*
Y324500D03*
X1265000Y426500D03*
X1253000Y511000D03*
X1251500Y531500D03*
X1260500Y546400D03*
X1263500Y550000D03*
X1258000Y555400D03*
X1255000Y609300D03*
X1266500Y617500D03*
X1265500Y652500D03*
X1257100Y664300D03*
X1263121Y678621D03*
X1266000Y665600D03*
X1262500Y699825D03*
X1253500Y778465D03*
X1257950Y809250D03*
X1279500Y150500D03*
X1276500Y234000D03*
X1267677Y232500D03*
X1280500Y338000D03*
Y404550D03*
X1280000Y420500D03*
X1272500Y466600D03*
X1271000Y573500D03*
X1282500Y598000D03*
X1274500Y606000D03*
X1278500Y603500D03*
X1271000Y617500D03*
X1279340Y618660D03*
X1282500Y645000D03*
X1272451Y642500D03*
X1272502Y638900D03*
X1268805Y655405D03*
X1282300Y678000D03*
X1282500Y669561D03*
X1273702Y667662D03*
X1275885Y670525D03*
X1267500Y675000D03*
Y684878D03*
X1281500Y713000D03*
X1279000Y746575D03*
X1267500Y783000D03*
X1269500Y835000D03*
X1299500Y236000D03*
X1292500Y402000D03*
X1289000Y415500D03*
X1285700Y529700D03*
X1293960Y528740D03*
X1294600Y524200D03*
X1291300Y540900D03*
X1294000Y587500D03*
X1288335Y594048D03*
X1287482Y590500D03*
X1293500Y593000D03*
X1285557Y585000D03*
X1289570Y597430D03*
X1284825Y621500D03*
X1294000Y628000D03*
X1299000Y641500D03*
X1296000Y638500D03*
X1290500Y635500D03*
X1286500Y652500D03*
X1297500Y665000D03*
X1291500Y666000D03*
X1289500Y669000D03*
X1296500Y830782D03*
X1306000Y43000D03*
X1304050Y296500D03*
X1307500Y320500D03*
X1308000Y311000D03*
X1312750Y314000D03*
X1306000Y329000D03*
Y334500D03*
Y338500D03*
X1311000Y463500D03*
X1302000Y475000D03*
X1304700Y536000D03*
X1302500Y559500D03*
X1307900Y577412D03*
X1306617Y587512D03*
X1308817Y595412D03*
X1310500Y625000D03*
X1311000Y651900D03*
X1310425Y660062D03*
X1311100Y656400D03*
X1304400Y661400D03*
X1311700Y681500D03*
X1312115Y672000D03*
X1311300Y687500D03*
X1313500Y710000D03*
X1305000Y739750D03*
X1308100Y748200D03*
X1312500Y838000D03*
X1305000Y850500D03*
X1312000D03*
X1314500Y921500D03*
X1322500Y299000D03*
X1324000Y290500D03*
X1322500Y337000D03*
X1317000Y336000D03*
X1330500Y441000D03*
X1332000Y459250D03*
X1323500Y452500D03*
X1325950Y599000D03*
X1323117Y626412D03*
X1329468Y666468D03*
X1323500Y702000D03*
X1322000Y705500D03*
X1325250Y834250D03*
X1316500Y839000D03*
X1317000Y850500D03*
X1318113Y846371D03*
X1339000Y54000D03*
X1347000Y48000D03*
X1342500Y51000D03*
X1333100Y58600D03*
X1343500Y112000D03*
X1336500Y270874D03*
X1339000Y274000D03*
X1339500Y305500D03*
X1341873Y344873D03*
X1335000Y443250D03*
X1335317Y575412D03*
X1347617Y610412D03*
X1346617Y626912D03*
X1342367Y627662D03*
X1334500Y636000D03*
X1333468Y680000D03*
X1334500Y669000D03*
X1352000Y85500D03*
X1349500Y112000D03*
X1350000Y276500D03*
X1350084Y296500D03*
X1353000Y390000D03*
Y402000D03*
X1362500Y459000D03*
X1353500Y466500D03*
X1351000Y455750D03*
X1356817Y579012D03*
X1364617Y592912D03*
X1360200Y614800D03*
X1363100Y627000D03*
X1349817Y628612D03*
X1357300Y617700D03*
X1379500Y274500D03*
X1381500Y292000D03*
X1376000D03*
X1379500Y314000D03*
X1370500Y356500D03*
X1374500Y462800D03*
X1367617Y570012D03*
X1390004Y122600D03*
X1384500Y274500D03*
Y331500D03*
G54D46*
X1379862Y108465D03*
Y119095D03*
G54D42*
X1258504Y329331D03*
Y368701D03*
G54D41*
X1224016Y386221D03*
G54D12*
X21220Y373228D03*
X96890D03*
X157480Y283071D03*
X220472D03*
G54D18*
X121890Y269528D03*
X131890D03*
X141890D03*
X1346396Y21656D03*
X1338526D03*
X1346396Y29526D03*
X1362146Y21656D03*
X1354271D03*
X1362146Y29526D03*
X1354271D03*
X1377896Y21656D03*
X1370021D03*
X1377896Y29526D03*
X1370021D03*
X1385766Y21656D03*
Y29526D03*
G54D19*
X121000Y545500D03*
X146364Y296000D03*
X156500Y939500D03*
X162000D03*
X168000Y575000D03*
Y580000D03*
X178000Y590000D03*
X167500Y939500D03*
X172500D03*
X177500D03*
X182000D03*
X188000D03*
X193500D03*
X199500D03*
X207100Y703600D03*
X222000Y703500D03*
X224000Y875000D03*
X225500Y879500D03*
X225000Y920500D03*
X232000Y921000D03*
X227500Y957500D03*
Y963500D03*
X247500Y883000D03*
X243000D03*
X246968Y957784D03*
X233468Y957284D03*
X239968Y957784D03*
X246968Y963784D03*
X239968D03*
X233468D03*
X261500Y188900D03*
X256300Y188800D03*
X258800Y184200D03*
X261400Y179800D03*
X255800Y179600D03*
X259000Y211000D03*
Y206000D03*
X262500Y208500D03*
X260000Y260000D03*
X252000Y883000D03*
X256500D03*
X261000D03*
X265500D03*
X252000Y957500D03*
X252500Y963500D03*
X281800Y183700D03*
Y188500D03*
X281900Y178500D03*
X278500Y965000D03*
X277500Y969500D03*
X272500D03*
X268000D03*
X296000Y105000D03*
X285800Y180800D03*
X285600Y186100D03*
X306000Y105000D03*
X301000D03*
X310929Y257500D03*
X311429Y334500D03*
X307429Y336000D03*
Y331500D03*
X321000Y29000D03*
Y33500D03*
Y38000D03*
X330500Y38500D03*
Y33500D03*
X321000Y57000D03*
Y52500D03*
Y48000D03*
Y42500D03*
Y61500D03*
X315929Y253000D03*
Y257500D03*
X336000Y27000D03*
X337500Y102000D03*
X362500Y64000D03*
X351929Y266000D03*
X357661Y434216D03*
X364055Y428500D03*
X361055Y431500D03*
X370000Y51000D03*
Y55500D03*
Y60000D03*
X370500Y72100D03*
X403155Y437600D03*
X445395Y317610D03*
X432678Y827300D03*
X430778Y864000D03*
X453878Y824900D03*
X456278Y866500D03*
X482429Y139000D03*
X482778Y832000D03*
X482278Y867500D03*
X495000Y883000D03*
X501000Y876000D03*
X499000Y883000D03*
X516000Y134000D03*
X519929Y135500D03*
X516500Y556000D03*
X591000Y253500D03*
Y262500D03*
X586000Y267000D03*
Y262500D03*
X591000Y258000D03*
X593500Y648500D03*
Y659500D03*
Y654000D03*
X595500Y253500D03*
Y258000D03*
X610000Y415500D03*
Y434000D03*
Y428500D03*
Y422000D03*
X610100Y439500D03*
X602500Y465900D03*
X608000Y465800D03*
X602500Y470100D03*
X608000Y470300D03*
X601000Y543000D03*
X599500Y648500D03*
Y654000D03*
Y659500D03*
X609500Y778500D03*
X603000D03*
Y785000D03*
X609000Y870000D03*
X604000Y877500D03*
X609211Y877611D03*
X614200Y415500D03*
X614500Y434000D03*
X614200Y422000D03*
Y428500D03*
X614300Y439500D03*
X620000Y465800D03*
X613500D03*
X626500D03*
X613500Y470000D03*
X620000D03*
X626500D03*
Y557350D03*
X637500Y367900D03*
X630500Y368500D03*
X642000D03*
X647500D03*
X653500D03*
X659500D03*
X645500Y481000D03*
X674666Y82002D03*
X670998Y116010D03*
X665000Y368500D03*
X670000Y395000D03*
X670500Y414000D03*
X685898Y133380D03*
X682418Y129980D03*
X685000Y150500D03*
X701949Y118331D03*
X701828Y129550D03*
X698500Y132500D03*
X697248Y128000D03*
X719500Y185600D03*
X725000Y189000D03*
X720000Y849000D03*
X721900Y852750D03*
X730748Y99500D03*
X740000Y109534D03*
X732248Y140000D03*
X731716Y156500D03*
X736000Y142000D03*
X740000Y681000D03*
X740500Y755000D03*
X739900Y760000D03*
X757000Y435500D03*
X752100Y435600D03*
X751500Y431000D03*
X756500D03*
X757802Y474000D03*
X773000Y339500D03*
X761600Y435600D03*
X761500Y431000D03*
X766000D03*
X770000Y677000D03*
Y681500D03*
X767000Y845000D03*
X773000Y917000D03*
Y921500D03*
Y927000D03*
X767500D03*
X771000Y958500D03*
X766600D03*
X762100Y958600D03*
X771500Y963500D03*
X767100D03*
X762600Y963600D03*
X771400Y968900D03*
X767000D03*
X762500Y969000D03*
X777500Y339500D03*
X782400Y339400D03*
X782600Y411000D03*
X792000Y356500D03*
X801500Y573000D03*
X819000Y473000D03*
X828500Y361500D03*
X837000D03*
X846500Y362000D03*
X842000Y367000D03*
Y372000D03*
Y377500D03*
X848600Y517100D03*
X843100Y517000D03*
X843200Y512800D03*
X843300Y507900D03*
X848800Y508000D03*
X848700Y512900D03*
X854500Y778000D03*
X850000D03*
X854500Y783000D03*
X850000D03*
X858500Y656500D03*
X879736Y290000D03*
X875500Y290500D03*
X878500Y294178D03*
X884000Y396500D03*
X879500D03*
X889000Y617000D03*
X895000Y96000D03*
X899500Y92500D03*
X899000Y405500D03*
X894000D03*
X899000Y410500D03*
X894000D03*
X895000Y617500D03*
X930500Y536500D03*
X943500Y488000D03*
X966000Y209500D03*
X961000Y212500D03*
X963500Y488000D03*
Y536500D03*
X981000Y386500D03*
X985000Y388000D03*
X980500Y391000D03*
X984500Y392500D03*
X1004500Y84000D03*
X1013500D03*
X1009000D03*
X1016500Y75500D03*
X1022500Y51500D03*
X1034500D03*
X1028000D03*
X1021000Y75500D03*
X1033000Y290000D03*
X1027500D03*
X1027700Y294200D03*
X1033200D03*
X1035500Y825500D03*
Y830000D03*
X1053000Y228000D03*
X1046000Y290000D03*
X1039500D03*
X1039700Y294200D03*
X1046200D03*
X1040000Y825500D03*
X1044500D03*
X1049000D03*
X1053400D03*
X1040000Y830000D03*
X1057000Y229500D03*
X1056716Y224500D03*
X1060000Y929500D03*
X1086000Y187500D03*
Y192500D03*
X1079000Y434000D03*
X1085000D03*
X1079100Y429000D03*
X1101500Y461500D03*
X1102500Y762500D03*
X1097500D03*
X1102500Y767400D03*
X1097500D03*
X1093000Y766500D03*
X1097500Y797500D03*
X1106600Y753000D03*
X1134000Y229000D03*
X1128500D03*
X1161500Y222000D03*
X1166500D03*
X1160500Y242000D03*
Y246500D03*
X1165000Y242000D03*
Y246500D03*
X1171000Y222000D03*
X1176000D03*
X1169000Y398000D03*
X1171000Y394000D03*
X1170500Y461000D03*
X1173100Y499200D03*
X1182000Y816000D03*
X1181500Y820500D03*
X1177000D03*
X1199100Y226600D03*
X1194900D03*
X1195000Y422500D03*
X1194000Y484000D03*
X1189500D03*
X1194000Y488500D03*
X1189500D03*
Y492900D03*
X1194000Y493000D03*
X1188500Y500000D03*
X1195920Y753700D03*
X1203500Y193800D03*
Y198000D03*
X1208000D03*
Y193800D03*
X1204000Y206000D03*
X1208500Y207000D03*
X1204000Y210500D03*
Y215000D03*
X1207500Y225000D03*
X1203300Y226600D03*
X1217000Y537000D03*
X1249300Y166000D03*
X1240600Y167000D03*
X1240700Y171200D03*
X1240800Y179800D03*
X1240700Y175500D03*
Y184000D03*
X1241000Y219000D03*
X1239500Y227500D03*
X1242000Y223500D03*
X1244000Y227500D03*
X1246000Y263500D03*
X1263000Y717000D03*
X1287500Y428000D03*
X1308500Y771500D03*
X1303000D03*
X1314000D03*
X1324500Y345400D03*
Y341000D03*
X1329000Y341100D03*
Y345500D03*
X1323000Y368000D03*
X1327500D03*
X1332000D03*
Y372400D03*
X1327500D03*
X1323000D03*
X1338000Y341100D03*
X1333500D03*
Y345500D03*
X1338000D03*
X1358500Y346500D03*
Y351000D03*
X1354000D03*
Y346500D03*
X1354500Y480500D03*
Y475000D03*
X1360500D03*
Y480500D03*
X1354500Y486500D03*
X1360500D03*
X1351000Y677000D03*
Y672000D03*
X1355000Y674500D03*
X1354500Y669000D03*
Y703500D03*
X1371500Y254000D03*
X1366000D03*
X1371500Y264000D03*
X1366000D03*
X1371500Y259500D03*
X1366000D03*
G54D22*
X180118Y729409D03*
Y739409D03*
X200118Y729409D03*
X190118D03*
X210118D03*
X220118D03*
X250118D03*
X240118D03*
G54D35*
X599941Y70118D03*
X607933D03*
X595905Y80118D03*
X603897D03*
X611889D03*
X615925Y70118D03*
X623917D03*
X627953Y80118D03*
X631909Y70118D03*
X639901D03*
X635945Y80118D03*
X643937D03*
G54D30*
X545079Y290355D03*
X560829D03*
X549014Y298230D03*
X556889Y308070D03*
X552954Y315945D03*
X549014Y308070D03*
X576574Y290355D03*
X564764Y298230D03*
X572639Y308070D03*
X568699Y315945D03*
X592324Y290355D03*
X580514Y298230D03*
X588384Y308070D03*
X584449Y315945D03*
X608069Y290355D03*
X596259Y298230D03*
X604134Y308070D03*
X600199Y315945D03*
X627754Y298230D03*
X623819Y290355D03*
X612009Y298230D03*
X619884Y308070D03*
X615944Y315945D03*
X643504Y298230D03*
X639569Y290355D03*
X635629Y308070D03*
X631694Y315945D03*
X659254Y298230D03*
X655314Y290355D03*
X651379Y308070D03*
X647439Y315945D03*
X674999Y298230D03*
X671064Y290355D03*
X667124Y308070D03*
X663189Y315945D03*
X690749Y298230D03*
X686809Y290355D03*
X682874Y308070D03*
X678939Y315945D03*
X706494Y298230D03*
X702559Y290355D03*
X698624Y308070D03*
X694684Y315945D03*
X722244Y298230D03*
X718309Y290355D03*
X726179Y315945D03*
X714369Y308070D03*
X710434Y315945D03*
X737994Y298230D03*
X734054Y290355D03*
X741929Y315945D03*
X730119Y308070D03*
X753739Y298230D03*
X749804Y290355D03*
X757679Y315945D03*
X745864Y308070D03*
X769489Y298230D03*
X765549Y290355D03*
X773424Y315945D03*
X761614Y308070D03*
X785234Y298230D03*
X781299Y290355D03*
X789174Y315945D03*
X777364Y308070D03*
X800984Y298230D03*
X797049Y290355D03*
X804919Y315945D03*
X793109Y308070D03*
X816734Y298230D03*
X812794Y290355D03*
X820669Y315945D03*
X808859Y308070D03*
X840354Y298230D03*
X836419Y290355D03*
X832479Y298230D03*
X840354Y308070D03*
X836419Y315945D03*
X832479Y308070D03*
X856104Y298230D03*
X852164Y290355D03*
X848229Y298230D03*
X844289Y290355D03*
X856104Y308070D03*
X852164Y315945D03*
X844289D03*
X871849Y298230D03*
X867914Y290355D03*
X863974Y298230D03*
X871849Y308070D03*
X867914Y315945D03*
X863974Y308070D03*
G54D38*
X1066929Y43267D03*
X1057086D03*
X1074803D03*
X1272441Y7087D03*
X1299213D03*
G54D40*
X1224016Y180709D03*
G54D23*
X200000Y391500D03*
Y401500D03*
Y411500D03*
Y421500D03*
X216500Y391500D03*
Y401500D03*
Y411500D03*
Y421500D03*
X945197Y380000D03*
X968819D03*
X1296000Y319500D03*
Y329500D03*
X1367067Y42323D03*
Y78544D03*
X1392657Y42323D03*
Y78544D03*
G54D27*
X402953Y23622D03*
X413189D03*
X423425D03*
G54D32*
X590315Y9134D03*
Y19134D03*
X649527Y9134D03*
Y19134D03*
Y29134D03*
G54D15*
X35435Y373228D03*
X82675D03*
G54D43*
X1272677Y349016D03*
G54D28*
X412815Y349860D03*
X408857Y341928D03*
Y365550D03*
Y357676D03*
Y385237D03*
Y377363D03*
Y400985D03*
Y393111D03*
Y416733D03*
Y408859D03*
Y424607D03*
X424605Y345865D03*
Y369487D03*
Y361613D03*
Y353739D03*
Y385237D03*
Y393111D03*
X428542Y397048D03*
X420668Y400985D03*
X416731Y416733D03*
Y404922D03*
X424605Y412796D03*
X416731Y420670D03*
Y424607D03*
X440353Y369487D03*
X444290Y365550D03*
X440353Y353739D03*
X444290Y357676D03*
X432479Y369487D03*
Y361613D03*
X444290Y385237D03*
Y377363D03*
X440353Y381300D03*
X432479Y385237D03*
X436416Y377363D03*
X432479D03*
X440353Y389174D03*
X432479Y397048D03*
Y393111D03*
Y389174D03*
X444290Y400985D03*
X436416D03*
X440353Y412796D03*
X432479D03*
X460040Y349802D03*
X456103Y365550D03*
Y357676D03*
X460040Y369487D03*
Y361613D03*
X448227Y369487D03*
Y361613D03*
Y353739D03*
X456103Y385237D03*
Y377363D03*
X460040Y381300D03*
X448227D03*
X460040Y389174D03*
X448227D03*
X456103Y393111D03*
X460040D03*
Y397048D03*
X448227Y393111D03*
X452123Y416783D03*
X460040Y412796D03*
X448227D03*
X471851Y322243D03*
Y326180D03*
X463977Y330117D03*
X467914Y349802D03*
Y369487D03*
Y361613D03*
Y365550D03*
Y357676D03*
Y353739D03*
X463977Y365550D03*
Y357676D03*
Y385237D03*
X467914D03*
Y377363D03*
Y381300D03*
X463977Y377363D03*
Y393111D03*
Y400985D03*
X471851D03*
Y389174D03*
X475788Y412796D03*
X471851Y416733D03*
X467914Y412796D03*
X493855Y312700D03*
X488155Y315700D03*
X490455Y319200D03*
X481255Y320000D03*
X479725Y341928D03*
Y349802D03*
X491536Y369487D03*
Y361613D03*
X479725Y365550D03*
Y357676D03*
X491536Y381300D03*
X479725Y385237D03*
Y377363D03*
X491536Y397048D03*
Y389174D03*
X479725Y400985D03*
Y393111D03*
X491536Y412796D03*
Y404922D03*
X483662Y412796D03*
Y404922D03*
X479725Y416733D03*
X487599Y420670D03*
X505678Y310921D03*
X506000Y317500D03*
X498855Y311100D03*
X498955Y316900D03*
X495473Y334054D03*
Y341928D03*
Y385237D03*
Y377363D03*
Y400985D03*
Y393111D03*
X1020500Y882500D03*
Y887000D03*
X1011966Y893534D03*
X1020282Y911218D03*
X1034000Y155000D03*
X1021468Y866968D03*
X1032600Y867657D03*
X1031500Y884500D03*
X1035216Y884468D03*
X1035000Y888500D03*
Y880500D03*
Y970000D03*
X1039468Y155284D03*
X1048968D03*
X1053500Y153000D03*
X1044000D03*
X1048968Y150784D03*
X1039500Y151000D03*
X1048968Y159284D03*
X1039500Y159500D03*
X1053500Y157500D03*
X1044000D03*
X1045968Y185500D03*
X1039000Y884500D03*
X1051000Y883600D03*
Y888500D03*
X1065000Y154000D03*
X1057968Y155284D03*
X1058000Y150500D03*
Y159500D03*
X1060509Y177126D03*
X1058000Y889500D03*
Y902500D03*
Y896000D03*
X1055000Y970000D03*
X1084988Y154203D03*
X1080500Y153500D03*
X1077500Y150000D03*
X1085150Y158400D03*
X1075000Y970000D03*
X1105000D03*
X1125000D03*
X1145000D03*
X1175000D03*
X1195000D03*
X1215000D03*
X1259968Y444284D03*
X1260000Y448500D03*
X1264500Y446500D03*
X1260000Y440000D03*
X1264500Y442000D03*
X1257468Y478500D03*
X1278500Y448500D03*
Y444000D03*
X1274000Y447000D03*
X1269468Y444284D03*
Y448284D03*
X1278500Y439500D03*
X1269468Y439784D03*
X1274000Y442000D03*
X1270000Y477000D03*
X1288000Y442000D03*
X1292500Y441000D03*
X1318000Y369500D03*
Y375500D03*
Y381500D03*
X1330000Y428000D03*
X1331500Y432500D03*
X1344000Y434500D03*
X1340200D03*
Y438300D03*
X1343900Y438500D03*
X1343000Y466500D03*
G54D10*
X8590Y318590D03*
X4500Y329297D03*
Y349297D03*
Y369297D03*
Y389297D03*
Y409297D03*
Y429297D03*
Y449297D03*
Y469297D03*
Y489297D03*
Y509297D03*
Y529297D03*
Y549297D03*
Y569297D03*
Y589297D03*
Y609297D03*
Y629297D03*
Y649297D03*
Y669297D03*
Y689297D03*
Y709297D03*
Y729297D03*
Y749297D03*
Y769297D03*
Y789297D03*
Y809297D03*
Y829297D03*
Y849297D03*
X8442Y847311D03*
X4500Y869297D03*
Y889297D03*
Y909297D03*
Y929297D03*
Y949297D03*
Y969297D03*
X20000Y380000D03*
Y440000D03*
Y460000D03*
Y480000D03*
Y500000D03*
X50395Y384679D03*
X40945Y384710D03*
X48820Y412435D03*
X39370Y412673D03*
X40054Y823970D03*
X36004Y839500D03*
X38804Y906220D03*
X41500Y941500D03*
X46500Y944500D03*
X59840Y384679D03*
X67715Y412518D03*
X58270Y412485D03*
X60304Y663220D03*
X64304Y698720D03*
X63304Y706720D03*
X64272Y736004D03*
X55304Y849720D03*
X78740Y384915D03*
X69290Y384865D03*
X77165Y412590D03*
X76804Y662720D03*
X73804Y699720D03*
X81304Y710220D03*
X76272Y762504D03*
X77804Y773720D03*
X71804Y789720D03*
X73772Y822004D03*
X69804Y835720D03*
X83838Y848133D03*
X76804Y847720D03*
X81804Y888720D03*
X72770Y906488D03*
X95304Y663720D03*
X97737Y698653D03*
X96060Y762476D03*
X100804Y774720D03*
X99804Y799720D03*
X85804Y816220D03*
X87804Y835720D03*
X98304Y888220D03*
X97804Y940720D03*
X112654Y314453D03*
X111304Y663720D03*
X111907Y698617D03*
X115804Y798720D03*
X101804Y940720D03*
X112900Y988500D03*
X132500Y312500D03*
X124500Y316000D03*
X122874Y354709D03*
X132804Y894220D03*
X134874Y354709D03*
X147374D03*
X149100Y661100D03*
X143010Y676400D03*
X162595Y296709D03*
X153437Y320458D03*
X155874Y310209D03*
X152995Y329119D03*
X159674Y328609D03*
X159774Y320709D03*
X158874Y354709D03*
X166875Y678285D03*
X153500Y690275D03*
X163000Y901000D03*
X158000D03*
X172285Y296964D03*
X181889Y297303D03*
X183374Y328709D03*
X171874D03*
X171295Y320709D03*
X180315Y321209D03*
X170374Y354709D03*
X172040Y688960D03*
X181000Y901000D03*
X174500Y901500D03*
X168500Y901000D03*
X197245Y296571D03*
X196063Y319209D03*
X192874Y326209D03*
Y337907D03*
X189000Y347600D03*
X198000Y785000D03*
X191875Y803125D03*
X188000Y901000D03*
X197000D03*
Y897000D03*
X207086Y297418D03*
X205511Y320709D03*
X214960Y321044D03*
X204500Y470000D03*
X212500Y786000D03*
X204500Y817500D03*
X205500Y901000D03*
Y897000D03*
X217295Y296709D03*
X231500Y898500D03*
X242500Y565500D03*
X240000Y829250D03*
X236500Y866000D03*
X261500Y857500D03*
X262178Y976000D03*
X261178Y981040D03*
X273000Y674000D03*
X269000Y921500D03*
X274000D03*
X273678Y958000D03*
X268178Y955500D03*
X297929Y332000D03*
Y336000D03*
X285500Y330000D03*
X286000Y336000D03*
X285678Y995500D03*
X293178D03*
X299500Y5500D03*
X311500Y153000D03*
X299000Y148000D03*
X307129Y143000D03*
X305029Y147700D03*
X304300Y160200D03*
X304100Y167000D03*
X311300D03*
X312500Y159100D03*
X305429Y219400D03*
Y223000D03*
X311500Y272000D03*
X307500Y299000D03*
X303545Y445840D03*
X300112Y483783D03*
X305155Y504900D03*
X305255Y542600D03*
X301178Y995500D03*
X309678D03*
X320500Y11000D03*
X316000D03*
X324000Y24000D03*
Y19500D03*
Y15000D03*
X316900Y65900D03*
X320500Y66000D03*
X330250Y80000D03*
X317660Y96400D03*
X330000Y118500D03*
X325929D03*
X330900Y134500D03*
X329929Y128500D03*
X319014Y152977D03*
X328700Y154400D03*
X328629Y146800D03*
X330400Y141600D03*
X318200Y159100D03*
X329929Y241500D03*
X316000Y271500D03*
X326000Y292500D03*
X322429Y349300D03*
X320238Y497183D03*
X316273Y520282D03*
X321555Y534500D03*
X315135Y554980D03*
X324678Y995500D03*
X317178D03*
X336700Y4300D03*
X341200D03*
X346000Y4400D03*
X344000Y27000D03*
X334500Y118500D03*
X337400Y134500D03*
X334000Y147600D03*
X345929Y183000D03*
X340679Y204900D03*
X332429Y210000D03*
X346404Y260000D03*
X345929Y336500D03*
X341351Y336434D03*
X344929Y325500D03*
X335645Y445630D03*
X343095Y446200D03*
X338595Y482590D03*
X339140Y512500D03*
X336445Y509330D03*
X343555Y517000D03*
X340715Y545840D03*
X339500Y936500D03*
X333500Y954000D03*
X341178Y996000D03*
X332678Y995500D03*
X355000Y4400D03*
X350500D03*
X360400D03*
X349000Y38500D03*
Y33500D03*
X352500Y113000D03*
X353085Y187485D03*
X354540Y199000D03*
X353300Y218400D03*
X352429Y279000D03*
X357929Y277000D03*
X348000Y292500D03*
X357055Y385000D03*
Y380500D03*
Y376500D03*
X355055Y394000D03*
Y389500D03*
X364055Y512000D03*
X351815Y546880D03*
X362500Y608500D03*
X355500D03*
Y614000D03*
X362500D03*
X364000Y869500D03*
X358268Y995500D03*
X348678Y996000D03*
X364900Y4400D03*
X369400D03*
X371482Y133058D03*
X365133Y129133D03*
X377759Y152000D03*
X365146Y151942D03*
X365182Y142532D03*
X374577Y164559D03*
X377750Y170846D03*
X374570Y158267D03*
X365176Y161400D03*
X368336Y189755D03*
X368307Y196062D03*
Y202361D03*
X377755D03*
Y199211D03*
Y196062D03*
Y192912D03*
Y189763D03*
X374607Y218110D03*
X374606Y211810D03*
X366000Y277500D03*
X371555Y347500D03*
X375805Y380250D03*
X371781Y387924D03*
X373555Y482500D03*
X367555Y545500D03*
X376500Y608500D03*
X369500D03*
Y614000D03*
X376500D03*
X380000Y872000D03*
X371938Y922438D03*
X377953Y995725D03*
X393800Y25100D03*
X389300Y20100D03*
X393800D03*
X384800Y25100D03*
X389300D03*
X384800Y20100D03*
X391000Y35500D03*
X395500D03*
X393900Y30400D03*
X389400D03*
X384900D03*
X386000Y53000D03*
X381500D03*
Y58000D03*
X392240Y129000D03*
X383680Y129030D03*
X390339Y151990D03*
X396639D03*
X380888Y148799D03*
X380928Y167701D03*
X393528Y167702D03*
X393542Y186614D03*
X393490Y174039D03*
X393541Y180315D03*
X384055Y202361D03*
X393503Y205510D03*
X396654Y202362D03*
X396653Y205511D03*
X393519Y192900D03*
X387209Y192930D03*
X393503Y211809D03*
X380906Y211810D03*
X396654D03*
X396653Y208660D03*
X393503D03*
X390354Y218109D03*
Y221259D03*
Y224408D03*
X391000Y238500D03*
X394929Y247000D03*
X386755Y447300D03*
X396055Y456500D03*
X389000Y604000D03*
X395500Y867000D03*
X396500Y910500D03*
X383500Y938500D03*
X389763Y996085D03*
X398300Y20100D03*
Y25100D03*
X400000Y35500D03*
X398400Y30400D03*
X398000Y39500D03*
X402800Y129180D03*
X402938Y151950D03*
X399827Y167702D03*
X406140Y167716D03*
X406127Y161404D03*
X412427D03*
X412426Y167703D03*
X399841Y186614D03*
X399840Y180315D03*
X399790Y174039D03*
X406126Y174003D03*
X406139Y180315D03*
X406101Y186613D03*
X412426Y174003D03*
X412439Y186614D03*
X412400Y180314D03*
X412401Y205510D03*
X406128Y192901D03*
X399791Y192938D03*
X412428Y192901D03*
X402953Y211810D03*
X412402D03*
X399803Y218109D03*
Y221259D03*
Y208660D03*
X409929Y245400D03*
X412513Y294800D03*
X398385Y292540D03*
X410500Y885500D03*
X401500Y994500D03*
X413540Y128500D03*
X418726Y167703D03*
Y174003D03*
Y180303D03*
X418701Y186614D03*
X424999Y202361D03*
X428149D03*
X418727Y192902D03*
X418701Y211810D03*
X425001D03*
X420429Y246400D03*
X416500Y284800D03*
X422500Y271501D03*
X425178Y798000D03*
X418278Y828000D03*
Y840000D03*
X418500Y857500D03*
X418278Y854000D03*
Y846500D03*
X419500Y914000D03*
X425000Y994500D03*
X434414Y205514D03*
X434449Y211810D03*
X436500Y241000D03*
X439000Y254500D03*
X440500Y267000D03*
X444255Y283700D03*
X430900Y294550D03*
X436416Y357676D03*
X432178Y798000D03*
X438178Y798500D03*
X444678Y798400D03*
X442278Y846000D03*
X431500Y886000D03*
X437678D03*
X443178D03*
X435678Y996000D03*
X443178D03*
X458429Y185000D03*
X459500Y290100D03*
X448000Y346000D03*
X456178Y798000D03*
X452978Y805400D03*
X455278Y846000D03*
X451278D03*
X459278D03*
X451178Y886000D03*
X460678D03*
X457578Y879700D03*
X458678Y996000D03*
X450178D03*
X469000Y113000D03*
X472990Y113350D03*
X462700Y120800D03*
X467000Y118500D03*
X465679Y192600D03*
X469155Y297800D03*
X474755Y308300D03*
X475678Y798500D03*
X463178D03*
X469178D03*
X467278Y846000D03*
X468178Y886000D03*
X472178D03*
X474178Y995500D03*
X466178Y996000D03*
X481929Y126500D03*
X490100Y162100D03*
X482178Y886000D03*
X489678Y995500D03*
X482178D03*
X503929Y127500D03*
X499629Y178400D03*
X498855Y302851D03*
X496155Y321700D03*
X497778Y843000D03*
Y838500D03*
Y847000D03*
X498500Y867500D03*
X505678Y995500D03*
X498178D03*
X525679Y136250D03*
X517679Y125750D03*
X513407Y311502D03*
X513500Y315800D03*
X522345Y311699D03*
X522365Y316365D03*
X521800Y322000D03*
X527667Y322182D03*
X523500Y347500D03*
Y352000D03*
Y342000D03*
X523100Y364300D03*
X526800Y359600D03*
X523500Y357500D03*
X521055Y528500D03*
Y533500D03*
X516555Y528500D03*
Y533500D03*
X526055D03*
X526000Y524500D03*
Y529000D03*
X521000Y524000D03*
X521055Y544000D03*
Y548900D03*
X516555Y543500D03*
X516655Y548900D03*
X521055Y538500D03*
X516555Y539000D03*
X526055Y538500D03*
Y544000D03*
Y548900D03*
X521500Y632500D03*
X521178Y995500D03*
X513678D03*
X538875Y138000D03*
X542000Y249000D03*
X528600Y316700D03*
X539300Y317600D03*
X534000Y317500D03*
X539200Y324100D03*
X530000Y342000D03*
X529400Y352800D03*
X530100Y347200D03*
X536678Y996000D03*
X530083Y995500D03*
X546500Y147500D03*
X547500Y360168D03*
X560678Y996000D03*
X577000Y58000D03*
X568500Y147500D03*
X574000Y269000D03*
X563250Y262500D03*
X571555Y326000D03*
X562055Y347500D03*
X567500Y457500D03*
X563000Y453000D03*
X567500D03*
Y462000D03*
Y466500D03*
X563000Y457500D03*
Y462000D03*
Y466500D03*
X569178Y996000D03*
X576678D03*
X579221Y237250D03*
X580828Y260028D03*
X586150Y383000D03*
X586200Y378500D03*
X581950Y383000D03*
X582000Y378500D03*
X590500Y383000D03*
X586150Y396000D03*
X590500D03*
X581950D03*
X586150Y409500D03*
X581950D03*
X590500D03*
X582700Y431500D03*
X590500Y423500D03*
X586150D03*
X587000Y431500D03*
X578500D03*
X581950Y423500D03*
X582200Y439500D03*
X578000D03*
X586500D03*
X584678Y994500D03*
X604500Y205000D03*
Y200500D03*
X603500Y218500D03*
Y214000D03*
X594500Y236000D03*
X610500Y333000D03*
X606000Y341500D03*
X609000Y345500D03*
X598178Y983500D03*
X615000Y333000D03*
X620500D03*
X611500Y341500D03*
X613500Y345500D03*
X616500Y341500D03*
X621500D03*
X642000Y335000D03*
X639000Y332000D03*
X638500Y409000D03*
X634500Y427000D03*
X637000Y431500D03*
X632500D03*
X637000Y436500D03*
X632500D03*
X641625Y465375D03*
X628250Y570200D03*
X646500Y101000D03*
X650500D03*
X651500Y408500D03*
X646500D03*
X647125Y429375D03*
X656162Y472338D03*
X654500Y494000D03*
X647252Y576500D03*
X662248Y101000D03*
X670454Y94544D03*
X667748Y104000D03*
X670522Y130200D03*
X673500Y334000D03*
X668000D03*
X662000D03*
X663500Y452000D03*
X672500D03*
X660000Y443500D03*
X663500Y456000D03*
Y460500D03*
X667500Y454000D03*
Y458500D03*
X672500Y456000D03*
Y460500D03*
X690966Y142028D03*
X687055Y258500D03*
X683055D03*
X678055D03*
X681000Y452000D03*
X690500Y468000D03*
X681000Y456000D03*
Y460500D03*
X676500Y454000D03*
Y458500D03*
X690000Y460500D03*
X687968Y755284D03*
Y781784D03*
X700000Y60500D03*
X703053Y133568D03*
X704716Y156520D03*
X700216Y156368D03*
X706055Y258500D03*
X705500Y352500D03*
X707000Y340500D03*
X708500Y365000D03*
X707000Y385000D03*
Y378000D03*
X708500Y371000D03*
X694000Y483500D03*
X693500Y472000D03*
X694000Y492000D03*
Y500500D03*
Y507500D03*
Y514000D03*
X705900Y569200D03*
X698818Y759350D03*
X703328Y800144D03*
X697250Y876750D03*
X715716Y82652D03*
X713716Y121284D03*
X721716Y112784D03*
Y116784D03*
X717716Y121284D03*
X721716D03*
Y129284D03*
Y125284D03*
X722716Y156520D03*
X718216D03*
X713716D03*
X709216D03*
X721200Y205800D03*
X710055Y258500D03*
X714055D03*
X711500Y385000D03*
Y378000D03*
X720500Y478750D03*
X723168Y774984D03*
X712500Y859750D03*
X716250Y860250D03*
X723000Y996500D03*
X729716Y121284D03*
X725716D03*
X727248Y141500D03*
X727216Y156520D03*
X733498Y180750D03*
X733000Y193000D03*
X732500Y485500D03*
X734500Y547500D03*
X734462Y553538D03*
X733268Y757984D03*
X735000Y780500D03*
X727468Y819284D03*
X733440Y875560D03*
X731498Y996500D03*
X739368Y996610D03*
X727558Y996500D03*
X757200Y103100D03*
X746716Y130238D03*
X750916Y130272D03*
X745500Y145000D03*
X756000Y180000D03*
X749750Y454000D03*
X755300Y489300D03*
X746750Y571750D03*
X748000Y579500D03*
X745400Y877600D03*
X761000Y88500D03*
Y82500D03*
X760600Y94500D03*
X760522Y116784D03*
X770000Y123500D03*
X770500Y136000D03*
X770900Y144300D03*
X765116Y187659D03*
X771000Y464000D03*
X765009Y563491D03*
X760125Y666875D03*
X770646Y685354D03*
X777500Y351000D03*
X782500D03*
X788600Y449300D03*
X784800D03*
X776468Y447600D03*
X784900Y453000D03*
X788800D03*
X784274Y486274D03*
X790600Y547600D03*
X790000Y554500D03*
X785500Y666500D03*
X783746Y692754D03*
X787500Y783500D03*
X782750Y845750D03*
X781000Y877000D03*
X776750Y964750D03*
X806274Y434726D03*
X791000Y562000D03*
X802500Y579500D03*
X794000Y723500D03*
X791500Y783500D03*
X805250Y865750D03*
X794500Y897000D03*
X800500Y977500D03*
X794500D03*
X800500Y982000D03*
X794500D03*
X818500Y361600D03*
X813500Y367000D03*
X811000Y430500D03*
X810000Y735500D03*
X814000Y849500D03*
X810000Y980000D03*
X838055Y262500D03*
X829500Y373500D03*
Y380000D03*
Y385500D03*
X825500Y411100D03*
X826500Y436000D03*
X826000Y465078D03*
X831000Y598500D03*
X839250Y854500D03*
X826060Y863440D03*
X840000Y980000D03*
X847055Y262500D03*
X851555D03*
X854000Y436500D03*
X846250Y642250D03*
X854000Y640500D03*
X852500Y710500D03*
X842500Y719500D03*
X852600Y868500D03*
X872000Y75500D03*
X866112Y85626D03*
X865055Y262500D03*
X871500Y484000D03*
X871000Y639500D03*
X870500Y665060D03*
X861250Y649250D03*
X865500Y690500D03*
X860500Y734000D03*
X870000Y980000D03*
X888750Y324660D03*
X877000Y409500D03*
X874450Y463500D03*
X877500Y612500D03*
X884200Y636500D03*
X878500Y695500D03*
X902000Y63000D03*
X904600Y406600D03*
X900000Y980000D03*
X935000Y51500D03*
X937000Y63000D03*
X930500Y219000D03*
X936500D03*
X930500Y232000D03*
X936500D03*
Y225500D03*
X930500D03*
X934000Y448700D03*
X968085Y452065D03*
X963500Y654500D03*
X958000D03*
Y659500D03*
X963500D03*
X969000Y655100D03*
Y659500D03*
X980078Y204578D03*
X980960Y195257D03*
X974500Y655100D03*
Y659500D03*
X989000Y66500D03*
X996500Y167000D03*
X988660Y190500D03*
X998000Y461500D03*
X1001000Y771500D03*
X1007000Y12000D03*
X1012000Y43000D03*
X1017274Y219274D03*
X1013000Y282500D03*
X1012900Y275300D03*
X1007500Y487500D03*
X1011500Y642000D03*
Y648000D03*
X1007032Y879968D03*
X1010000Y980000D03*
X1032000Y82500D03*
Y90000D03*
Y97000D03*
Y103500D03*
Y110000D03*
X1036019Y203177D03*
X1036000Y199500D03*
X1035922Y209578D03*
X1031800Y248800D03*
X1027500Y248500D03*
X1036300Y248800D03*
X1041410Y695394D03*
Y690694D03*
X1042400Y684500D03*
X1041410Y708804D03*
Y704224D03*
Y699834D03*
X1042500Y930000D03*
X1040000Y980000D03*
X1066500Y185500D03*
X1060000Y207500D03*
X1060500Y282500D03*
X1060600Y303150D03*
X1056100Y303200D03*
X1059900Y295200D03*
X1059800Y290600D03*
X1065978Y664568D03*
X1063056Y681554D03*
X1062700Y672600D03*
X1061696Y761294D03*
X1061356Y753354D03*
X1071000Y71000D03*
X1077250Y102000D03*
X1077500Y97000D03*
Y107500D03*
X1086000Y126500D03*
X1074500Y185500D03*
X1072500Y208924D03*
X1074000Y660500D03*
Y677000D03*
X1073500Y672000D03*
X1074500Y665500D03*
X1074000Y683000D03*
X1074500Y694754D03*
X1074426Y687255D03*
X1074389Y691155D03*
X1074000Y699500D03*
X1074148Y711624D03*
X1074600Y707724D03*
X1074000Y703500D03*
X1073384Y722384D03*
X1073000Y730834D03*
Y726444D03*
X1074288Y715534D03*
X1077500Y745374D03*
X1072000Y743500D03*
X1077500Y759000D03*
X1085468Y895968D03*
X1070000Y980000D03*
X1088000Y85500D03*
X1098000Y126500D03*
X1102000Y250000D03*
X1102500Y264500D03*
X1089500Y405000D03*
X1098000Y775000D03*
X1093000Y791000D03*
X1097500Y784500D03*
X1098500Y823344D03*
X1092718Y859984D03*
X1093468Y896968D03*
X1100000Y980000D03*
X1111500Y718500D03*
X1107000Y757500D03*
X1114500Y855500D03*
X1119000D03*
X1118034Y847034D03*
X1113768D03*
X1116468Y870284D03*
Y874284D03*
Y865784D03*
X1112468Y870284D03*
X1114500Y886000D03*
X1103000Y888300D03*
X1118500Y886000D03*
X1123000Y250500D03*
X1120600Y282300D03*
X1129000Y502500D03*
X1123500D03*
Y507500D03*
X1129000D03*
X1135500D03*
Y502500D03*
X1134000Y613500D03*
X1126500Y614500D03*
X1132445Y714345D03*
X1132960Y752950D03*
X1126210Y752810D03*
X1134245Y769145D03*
X1127945Y769970D03*
X1121215Y769936D03*
X1135000Y810000D03*
X1134244Y799984D03*
X1121000Y808500D03*
X1127945Y799935D03*
X1121646Y799924D03*
X1121000Y823500D03*
X1123500Y832470D03*
X1135500Y835000D03*
X1135468Y854032D03*
X1120468Y870284D03*
X1131275Y867725D03*
X1130000Y980000D03*
X1145800Y282284D03*
X1151500Y449000D03*
X1141000Y507500D03*
Y502500D03*
X1135589Y682854D03*
Y695415D03*
X1145265Y776945D03*
X1151592Y773748D03*
X1140650Y782496D03*
X1151565Y787951D03*
X1142110Y792660D03*
X1149400Y800000D03*
X1142010Y809500D03*
X1137000Y890000D03*
X1144500D03*
X1152000D03*
X1166000Y232000D03*
X1162468Y257968D03*
X1168000Y302500D03*
X1166000Y290000D03*
X1168076Y310046D03*
X1152500Y311000D03*
X1158000Y309500D03*
X1152500Y318500D03*
X1160000D03*
X1167000Y321000D03*
Y326450D03*
X1154000Y589000D03*
X1160768Y676535D03*
X1154470Y673363D03*
X1152090Y677010D03*
X1163968Y708000D03*
X1160333Y753600D03*
X1167320Y770290D03*
X1157871Y773728D03*
X1167330Y795830D03*
X1163605Y783513D03*
X1167277Y792658D03*
X1157866Y795844D03*
X1165300Y809610D03*
X1160300D03*
X1154300D03*
X1155390Y818000D03*
X1157990Y827000D03*
X1158000Y890000D03*
X1164500D03*
X1155000Y980000D03*
X1171000Y232000D03*
X1177500Y290000D03*
X1174752Y320504D03*
X1175000Y327000D03*
X1176500Y383500D03*
X1182500Y407000D03*
X1179934Y567000D03*
X1173365Y695397D03*
X1169800Y682200D03*
X1182815Y701696D03*
X1182796Y708013D03*
X1184750Y781000D03*
X1170300Y809610D03*
X1186500Y232000D03*
X1196334Y290561D03*
X1185283Y290513D03*
X1198000Y348000D03*
X1192000Y344500D03*
X1197000Y372500D03*
X1187500Y411000D03*
X1197000Y409500D03*
X1190000Y699500D03*
X1188000Y762500D03*
X1198718Y800782D03*
X1188875Y856625D03*
X1185000Y980000D03*
X1208500Y202000D03*
X1209000Y212500D03*
X1208000Y231000D03*
X1201922Y248500D03*
X1202177Y260000D03*
X1208500Y283500D03*
X1208000Y271499D03*
Y297638D03*
Y309000D03*
X1206500Y330000D03*
X1208500Y321500D03*
X1203500Y345000D03*
X1208500Y346400D03*
Y359000D03*
X1208000Y371000D03*
X1209000Y438500D03*
X1209500Y561910D03*
X1213598Y699164D03*
X1216500Y710125D03*
X1201968Y757500D03*
X1212840Y781000D03*
X1204000Y862000D03*
X1217250Y862250D03*
X1211500Y882500D03*
X1215000Y980000D03*
X1221500Y633000D03*
X1229000Y726500D03*
X1230500Y841000D03*
X1239500Y204000D03*
Y214000D03*
X1239000Y251500D03*
X1241777Y265700D03*
X1241377Y274900D03*
X1238500Y290000D03*
X1239000Y302437D03*
X1238500Y316500D03*
X1250158Y326463D03*
X1238500Y325985D03*
X1239000Y338900D03*
Y352800D03*
X1239500Y366000D03*
X1234177Y379500D03*
X1243000Y446650D03*
X1248500Y775500D03*
X1248950Y782450D03*
X1245650Y821850D03*
X1245000Y980000D03*
X1256500Y166500D03*
X1261000D03*
X1265000Y169000D03*
Y174000D03*
X1258000Y205000D03*
X1265000Y211500D03*
X1261000Y207500D03*
Y211500D03*
X1251500Y266500D03*
X1251700Y274000D03*
X1254203Y282770D03*
X1261000Y292500D03*
X1261006Y303543D03*
X1252564Y290566D03*
X1253500Y316500D03*
Y305000D03*
X1257000Y311000D03*
X1265000Y647500D03*
X1257500Y635500D03*
X1265000Y661000D03*
Y657000D03*
X1259000Y678950D03*
X1262300Y670700D03*
X1264000Y853000D03*
X1281000Y475000D03*
X1276500D03*
X1271000Y568500D03*
X1281268Y661780D03*
X1277500Y757500D03*
Y778500D03*
X1267500Y779000D03*
X1275000Y980000D03*
X1290874Y34376D03*
X1295500Y291500D03*
X1285500Y475000D03*
X1293500D03*
X1297500Y562000D03*
X1286500Y569000D03*
X1284490Y710936D03*
X1298034Y907034D03*
X1309500Y51000D03*
X1311000Y435000D03*
X1307000Y573412D03*
X1306817Y592412D03*
X1312000Y645784D03*
X1311000Y677284D03*
X1306000Y782500D03*
X1314284D03*
X1304500Y838000D03*
X1300784Y838716D03*
X1303750Y862250D03*
X1307468Y884532D03*
X1300000Y980000D03*
X1331000Y120000D03*
X1322000Y318500D03*
X1319400Y522100D03*
X1318700Y533500D03*
X1326617Y594412D03*
X1329317Y626512D03*
X1328000Y649000D03*
X1328968Y679684D03*
X1318784Y793716D03*
X1321466Y907034D03*
X1330000Y980000D03*
X1347000Y88000D03*
X1347500Y116000D03*
X1334500Y557000D03*
X1344617Y588712D03*
Y593412D03*
X1342648Y612412D03*
X1354500Y276000D03*
X1358500Y288916D03*
X1354900Y522600D03*
X1355900Y536600D03*
X1355500Y556500D03*
X1360817Y557812D03*
X1349317Y593412D03*
X1353117Y610412D03*
X1353517Y627512D03*
X1360000Y631500D03*
X1355500Y631000D03*
X1358000Y626000D03*
X1357500Y635500D03*
X1360000Y980000D03*
X1369720Y106365D03*
X1375500Y328000D03*
X1378500Y370000D03*
Y365000D03*
Y360000D03*
X1377000Y384000D03*
Y379000D03*
X1378500Y374500D03*
X1377000Y390000D03*
X1374500Y395000D03*
Y402000D03*
X1372500Y415000D03*
X1368000Y450500D03*
X1369617Y557012D03*
X1378800Y594900D03*
X1390004Y106000D03*
G54D44*
X1338526Y29526D03*
G54D31*
X545079Y315945D03*
X556889Y298230D03*
X552954Y290355D03*
X560829Y315945D03*
X572639Y298230D03*
X568699Y290355D03*
X576574Y315945D03*
X564764Y308070D03*
X588384Y298230D03*
X584449Y290355D03*
X592324Y315945D03*
X580514Y308070D03*
X604134Y298230D03*
X600199Y290355D03*
X608069Y315945D03*
X596259Y308070D03*
X619884Y298230D03*
X615944Y290355D03*
X627754Y308070D03*
X623819Y315945D03*
X612009Y308070D03*
X635629Y298230D03*
X631694Y290355D03*
X643504Y308070D03*
X639569Y315945D03*
X651379Y298230D03*
X647439Y290355D03*
X659254Y308070D03*
X655314Y315945D03*
X667124Y298230D03*
X663189Y290355D03*
X674999Y308070D03*
X671064Y315945D03*
X682874Y298230D03*
X678939Y290355D03*
X690749Y308070D03*
X686809Y315945D03*
X698624Y298230D03*
X694684Y290355D03*
X706494Y308070D03*
X702559Y315945D03*
X726179Y290355D03*
X714369Y298230D03*
X710434Y290355D03*
X722244Y308070D03*
X718309Y315945D03*
X741929Y290355D03*
X730119Y298230D03*
X737994Y308070D03*
X734054Y315945D03*
X757679Y290355D03*
X745864Y298230D03*
X753739Y308070D03*
X749804Y315945D03*
X773424Y290355D03*
X761614Y298230D03*
X769489Y308070D03*
X765549Y315945D03*
X789174Y290355D03*
X777364Y298230D03*
X785234Y308070D03*
X781299Y315945D03*
X804919Y290355D03*
X793109Y298230D03*
X800984Y308070D03*
X797049Y315945D03*
X820669Y290355D03*
X808859Y298230D03*
X816734Y308070D03*
X812794Y315945D03*
X848229Y308070D03*
X860039Y290355D03*
Y315945D03*
G54D45*
X1367067Y60039D03*
Y96260D03*
X1392657Y60039D03*
Y96260D03*
G54D29*
X537994Y303150D03*
X825984D03*
G54D36*
X1008268Y244094D03*
Y411417D03*
X1227166Y155511D03*
X1227165Y411417D03*
G54D14*
X15000Y1008622D03*
X90119Y72219D03*
X227041Y1008622D03*
X653974Y1008621D03*
X955315Y850829D03*
X1157095Y128841D03*
X1385000Y1008622D03*
X1387875Y-15015D03*
G54D25*
X270078Y92125D03*
Y155117D03*
X490944Y79921D03*
Y255118D03*
X743897Y353543D03*
Y410629D03*
X1305117Y87548D03*
Y262745D03*
X1376968Y147243D03*
Y216535D03*
G54D37*
X1045000Y32598D03*
X1096732D03*
G54D34*
X600925Y44134D03*
X638917D03*
G54D26*
X332086Y408858D03*
X355708Y96456D03*
X450196Y257874D03*
X572243Y337992D03*
G54D16*
X25000Y980000D03*
X45000D03*
X55000Y975000D03*
X65000Y980000D03*
X75000Y975000D03*
X95000D03*
X206000Y982000D03*
X226000D03*
X246000D03*
X324500Y6000D03*
X1105000Y15000D03*
Y75000D03*
Y105000D03*
Y135000D03*
X1211500Y5500D03*
Y35500D03*
Y65500D03*
Y85500D03*
Y107500D03*
Y137500D03*
G54D20*
X140000Y720000D03*
Y740000D03*
X180000Y760000D03*
X220000D03*
X260000D03*
X378500Y812000D03*
Y824500D03*
X406500Y713500D03*
X412000Y724000D03*
X409500Y775500D03*
X422500Y764500D03*
X440000Y5000D03*
X431000Y713500D03*
Y724000D03*
X460000Y5000D03*
X477500Y715000D03*
X485000Y5000D03*
X491500Y715000D03*
X490500Y800000D03*
X504500Y715000D03*
X502500Y800000D03*
X515000Y5000D03*
X545000D03*
X560000Y20000D03*
X575000Y5000D03*
X604500Y714500D03*
X606000Y918500D03*
X616500Y714500D03*
X613500Y744500D03*
Y759000D03*
X620500Y848500D03*
X634000Y734500D03*
X633500Y749500D03*
X630500Y912000D03*
X650000Y110000D03*
X657500Y827000D03*
X656500Y906000D03*
X660000Y120000D03*
X685000Y5000D03*
X682500Y917500D03*
X695000Y20000D03*
X715000Y5000D03*
X725000Y20000D03*
X720000Y905000D03*
X728966Y53966D03*
Y65466D03*
X745000Y5000D03*
X755000Y20000D03*
X747800Y50200D03*
X762250Y71000D03*
X775000Y5000D03*
X785000Y20000D03*
X805000Y5000D03*
X800000Y100000D03*
X815000Y20000D03*
X810000Y120000D03*
X820500Y754000D03*
Y765500D03*
X835000Y5000D03*
X850000Y20000D03*
X865000Y5000D03*
X870000Y160000D03*
X880000Y20000D03*
X895000Y5000D03*
X890000Y140000D03*
X910000Y20000D03*
Y160000D03*
X915000Y805000D03*
Y825000D03*
Y845000D03*
Y865000D03*
Y885000D03*
Y905000D03*
Y925000D03*
Y945000D03*
Y965000D03*
X925000Y5000D03*
X955000D03*
X940000Y20000D03*
X970000D03*
X965000Y725500D03*
X985000Y5000D03*
X980000Y725500D03*
X1000000Y20000D03*
X1000500Y667500D03*
X990000D03*
X1015000Y5000D03*
X1045000D03*
X1060000Y20000D03*
X1075000Y5000D03*
X1090000Y20000D03*
X1100000Y180000D03*
X1091500Y846500D03*
X1105000Y5000D03*
Y400500D03*
X1235500Y5000D03*
X1268000D03*
X1307500D03*
X1306423Y608164D03*
X1306443Y618985D03*
X1337500Y5000D03*
X1379600Y584200D03*
X1377800Y603800D03*
X1378082Y614266D03*
X1381637Y611225D03*
X1381578Y607117D03*
X1394122Y5878D03*
X1387200Y584100D03*
X1384400Y598300D03*
Y601900D03*
G54D21*
X153937Y238898D03*
Y246772D03*
Y260551D03*
X224015Y234961D03*
Y246772D03*
Y260551D03*
G54D33*
X585315Y44134D03*
X654527D03*
G54D24*
X200118Y739409D03*
X190118D03*
X210118D03*
X230118Y729409D03*
Y739409D03*
X220118D03*
X250118D03*
X240118D03*
X260118Y729409D03*
Y739409D03*
X270118Y729409D03*
Y739409D03*
G54D11*
X19272Y337795D03*
Y396850D03*
X98838Y337795D03*
Y396850D03*
G54D39*
X1084646Y43267D03*
%LPC*%
G75*
G54D47*
G01X-245081Y-422119D02*
G02I-12000J0D01*
G01X-250231D02*
G02I-6850J0D01*
G01X-241081D02*
X-273081D01*
G01X-257081Y-438119D02*
Y-406119D01*
G01X-241081Y-438119D02*
Y-518119D01*
G01D02*
X1034819D01*
G01X-241081Y-473619D02*
X1034819D01*
G01X-241081Y-438119D02*
X1034819D01*
G01X247319D02*
Y-518119D01*
G01X384819Y-438119D02*
Y-518119D01*
G01X499819Y-438119D02*
Y-518119D01*
G01X667319Y-438119D02*
Y-518119D01*
G01X837319Y-438119D02*
Y-518119D01*
G01X1034819Y-438119D02*
Y-518119D01*
G01X1066819Y-422119D02*
X1034819D01*
G01X1050819Y-438119D02*
Y-406119D01*
G01X1062819Y-422119D02*
G02I-12000J0D01*
G01X1057669D02*
G02I-6850J0D01*
G54D48*
G01X-185516Y-508119D02*
Y-490619D01*
G01X-176346D02*
Y-508119D01*
G01Y-499369D02*
X-185516D01*
G01X-163431Y-508119D02*
X-165178Y-507827D01*
X-166706Y-506661D01*
X-168016Y-504911D01*
X-168890Y-502869D01*
X-169326Y-500536D01*
Y-498202D01*
X-168890Y-495869D01*
X-168016Y-493827D01*
X-166706Y-492078D01*
X-165178Y-490911D01*
X-163431Y-490619D01*
X-161685Y-490911D01*
X-160156Y-492078D01*
X-158846Y-493827D01*
X-157972Y-495869D01*
X-157536Y-498202D01*
Y-500536D01*
X-157972Y-502869D01*
X-158846Y-504911D01*
X-160156Y-506661D01*
X-161685Y-507827D01*
X-163431Y-508119D01*
G01X-150953D02*
Y-490619D01*
X-140909Y-508119D01*
Y-490619D01*
G01X-124064Y-508119D02*
X-132798D01*
Y-490619D01*
X-124064D01*
G01X-127558Y-499077D02*
X-132798D01*
G01X-110931Y-508119D02*
Y-500244D01*
X-115298Y-490619D01*
G01X-106564D02*
X-110931Y-500244D01*
G01X-74185Y-498786D02*
X-73311Y-497911D01*
X-72656Y-496453D01*
X-72219Y-494410D01*
X-72656Y-492661D01*
X-73529Y-491494D01*
X-75058Y-490619D01*
X-80953D01*
Y-508119D01*
X-73748D01*
X-72219Y-506953D01*
X-71346Y-505202D01*
X-70909Y-503161D01*
X-71346Y-501119D01*
X-72656Y-499369D01*
X-74185Y-498786D01*
X-80953D01*
G01X-63890Y-508119D02*
X-58431Y-490619D01*
X-52972Y-508119D01*
G01X-54938Y-501994D02*
X-61925D01*
G01X-45734Y-508119D02*
Y-490619D01*
X-41368D01*
X-39621Y-491494D01*
X-38311Y-492661D01*
X-37219Y-494410D01*
X-36346Y-496453D01*
X-36128Y-499369D01*
X-36346Y-502286D01*
X-37219Y-504328D01*
X-38311Y-506078D01*
X-39621Y-507244D01*
X-41368Y-508119D01*
X-45734D01*
G01X-22121Y-499369D02*
X-17754D01*
Y-504619D01*
X-19064Y-506369D01*
X-20593Y-507536D01*
X-22776Y-508119D01*
X-24959Y-507536D01*
X-26488Y-506369D01*
X-27798Y-504619D01*
X-28671Y-502577D01*
X-29108Y-500244D01*
Y-498202D01*
X-28671Y-496453D01*
X-27798Y-494410D01*
X-26488Y-492661D01*
X-25178Y-491494D01*
X-23431Y-490619D01*
X-21903D01*
X-20156Y-491202D01*
X-18846Y-492369D01*
G01X-1564Y-508119D02*
X-10298D01*
Y-490619D01*
X-1564D01*
G01X-5058Y-499077D02*
X-10298D01*
G01X7202Y-508119D02*
Y-490619D01*
X12661D01*
X14407Y-491494D01*
X15499Y-492661D01*
X15936Y-494994D01*
X15499Y-497328D01*
X14189Y-498786D01*
X12661Y-499661D01*
X7202D01*
G01X12661D02*
X15936Y-508119D01*
G01X48315Y-498786D02*
X49189Y-497911D01*
X49844Y-496453D01*
X50281Y-494410D01*
X49844Y-492661D01*
X48971Y-491494D01*
X47442Y-490619D01*
X41547D01*
Y-508119D01*
X48752D01*
X50281Y-506953D01*
X51154Y-505202D01*
X51591Y-503161D01*
X51154Y-501119D01*
X49844Y-499369D01*
X48315Y-498786D01*
X41547D01*
G01X58610Y-508119D02*
X64069Y-490619D01*
X69528Y-508119D01*
G01X67562Y-501994D02*
X60575D01*
G01X76984Y-505786D02*
X78731Y-507244D01*
X80696Y-508119D01*
X82442D01*
X84189Y-507244D01*
X85499Y-505786D01*
X86154Y-503744D01*
X85717Y-501703D01*
X84626Y-499952D01*
X82661Y-498786D01*
X80041Y-498202D01*
X78512Y-497036D01*
X77857Y-494994D01*
X78294Y-492952D01*
X79386Y-491494D01*
X80914Y-490619D01*
X82442D01*
X83971Y-491202D01*
X85281Y-492661D01*
G01X103436Y-508119D02*
X94702D01*
Y-490619D01*
X103436D01*
G01X99942Y-499077D02*
X94702D01*
G01X118315Y-498786D02*
X119189Y-497911D01*
X119844Y-496453D01*
X120281Y-494410D01*
X119844Y-492661D01*
X118971Y-491494D01*
X117442Y-490619D01*
X111547D01*
Y-508119D01*
X118752D01*
X120281Y-506953D01*
X121154Y-505202D01*
X121591Y-503161D01*
X121154Y-501119D01*
X119844Y-499369D01*
X118315Y-498786D01*
X111547D01*
G01X134069Y-508119D02*
X132322Y-507827D01*
X130794Y-506661D01*
X129484Y-504911D01*
X128610Y-502869D01*
X128174Y-500536D01*
Y-498202D01*
X128610Y-495869D01*
X129484Y-493827D01*
X130794Y-492078D01*
X132322Y-490911D01*
X134069Y-490619D01*
X135815Y-490911D01*
X137344Y-492078D01*
X138654Y-493827D01*
X139528Y-495869D01*
X139964Y-498202D01*
Y-500536D01*
X139528Y-502869D01*
X138654Y-504911D01*
X137344Y-506661D01*
X135815Y-507827D01*
X134069Y-508119D01*
G01X146110D02*
X151569Y-490619D01*
X157028Y-508119D01*
G01X155062Y-501994D02*
X148075D01*
G01X164702Y-508119D02*
Y-490619D01*
X170161D01*
X171907Y-491494D01*
X172999Y-492661D01*
X173436Y-494994D01*
X172999Y-497328D01*
X171689Y-498786D01*
X170161Y-499661D01*
X164702D01*
G01X170161D02*
X173436Y-508119D01*
G01X181766D02*
Y-490619D01*
X186132D01*
X187879Y-491494D01*
X189189Y-492661D01*
X190281Y-494410D01*
X191154Y-496453D01*
X191372Y-499369D01*
X191154Y-502286D01*
X190281Y-504328D01*
X189189Y-506078D01*
X187879Y-507244D01*
X186132Y-508119D01*
X181766D01*
G01X-37858Y-463119D02*
Y-445619D01*
X-32181Y-460202D01*
X-26504Y-445619D01*
Y-463119D01*
G01X-14681D02*
X-15991Y-462827D01*
X-17301Y-461661D01*
X-18175Y-459619D01*
X-18611Y-457286D01*
X-18175Y-454952D01*
X-17301Y-452911D01*
X-15991Y-451744D01*
X-14681Y-451453D01*
X-13371Y-451744D01*
X-12061Y-452911D01*
X-11188Y-454952D01*
X-10969Y-457286D01*
X-11188Y-459619D01*
X-12061Y-461661D01*
X-13371Y-462827D01*
X-14681Y-463119D01*
G01X6749Y-445619D02*
Y-463119D01*
G01Y-460495D02*
X5876Y-461953D01*
X4565Y-462827D01*
X3037Y-463119D01*
X1291Y-462536D01*
X-19Y-461078D01*
X-893Y-459328D01*
X-1111Y-457286D01*
X-893Y-455244D01*
X-19Y-453494D01*
X1291Y-452036D01*
X3037Y-451453D01*
X4565Y-451744D01*
X5657Y-452328D01*
X6749Y-453494D01*
G01X17044Y-455244D02*
X24031D01*
X23376Y-453202D01*
X22284Y-452036D01*
X20756Y-451453D01*
X19227Y-451744D01*
X17917Y-452619D01*
X17044Y-454661D01*
X16607Y-456411D01*
Y-458161D01*
X17044Y-459911D01*
X18136Y-461661D01*
X19446Y-462827D01*
X20974Y-463119D01*
X22502Y-462536D01*
X24031Y-460786D01*
G01X37819Y-463119D02*
Y-445619D01*
G01X281019Y-508119D02*
Y-490619D01*
X278399Y-494119D01*
G01Y-508119D02*
X283639D01*
G01X293716Y-504619D02*
X295025Y-506661D01*
X296772Y-507827D01*
X298737Y-508119D01*
X300484Y-507827D01*
X302231Y-506369D01*
X303322Y-504619D01*
X303541Y-502869D01*
X303104Y-500828D01*
X301576Y-499369D01*
X300047Y-498786D01*
X298082D01*
G01X300047D02*
X301357Y-497911D01*
X302449Y-496453D01*
X302886Y-494703D01*
X302449Y-492952D01*
X301357Y-491494D01*
X299392Y-490619D01*
X297427Y-490911D01*
X295462Y-492078D01*
G01X312307Y-506078D02*
X313836Y-507536D01*
X315582Y-508119D01*
X317329Y-507536D01*
X318857Y-505786D01*
X319949Y-503161D01*
X320386Y-500536D01*
Y-497328D01*
X319949Y-494703D01*
X318857Y-492369D01*
X317547Y-491202D01*
X316019Y-490619D01*
X314272Y-491202D01*
X312962Y-492369D01*
X312089Y-494119D01*
X311652Y-496453D01*
X312089Y-498494D01*
X313181Y-500536D01*
X314491Y-501703D01*
X316019Y-501994D01*
X317765Y-501411D01*
X319076Y-499952D01*
X320386Y-497328D01*
G01X336139Y-508119D02*
Y-490619D01*
X328060Y-503161D01*
X338978D01*
G01X351019Y-508119D02*
X352547Y-507827D01*
X354294Y-506953D01*
X355386Y-505495D01*
X355822Y-503452D01*
X355386Y-501411D01*
X354076Y-499661D01*
X352111Y-498786D01*
X349927D01*
X348617Y-498202D01*
X347525Y-496744D01*
X347089Y-494703D01*
X347744Y-492661D01*
X349272Y-491202D01*
X351019Y-490619D01*
X352765Y-491202D01*
X354294Y-492661D01*
X354949Y-494703D01*
X354512Y-496744D01*
X353421Y-498202D01*
X352111Y-498786D01*
X349927D01*
X347962Y-499661D01*
X346652Y-501411D01*
X346216Y-503452D01*
X346652Y-505495D01*
X347744Y-506953D01*
X349491Y-507827D01*
X351019Y-508119D01*
G01X267902Y-463119D02*
Y-445619D01*
X273142D01*
X274889Y-446494D01*
X276199Y-448536D01*
X276636Y-450869D01*
X276199Y-453202D01*
X275107Y-454952D01*
X273142Y-455828D01*
X267902D01*
G01X294572Y-447078D02*
X293262Y-446202D01*
X291734Y-445619D01*
X289987D01*
X288022Y-446494D01*
X286494Y-447952D01*
X285402Y-449703D01*
X284529Y-452619D01*
X284310Y-455244D01*
X284747Y-457869D01*
X285402Y-459619D01*
X286712Y-461369D01*
X288241Y-462536D01*
X289769Y-463119D01*
X291297D01*
X292826Y-462536D01*
X294136Y-461661D01*
X295228Y-460495D01*
G01X309015Y-453786D02*
X309889Y-452911D01*
X310544Y-451453D01*
X310981Y-449410D01*
X310544Y-447661D01*
X309671Y-446494D01*
X308142Y-445619D01*
X302247D01*
Y-463119D01*
X309452D01*
X310981Y-461953D01*
X311854Y-460202D01*
X312291Y-458161D01*
X311854Y-456119D01*
X310544Y-454369D01*
X309015Y-453786D01*
X302247D01*
G01X318219Y-468952D02*
X331319D01*
G01X337247Y-463119D02*
Y-445619D01*
X347291Y-463119D01*
Y-445619D01*
G01X359769Y-463119D02*
X358022Y-462827D01*
X356494Y-461661D01*
X355184Y-459911D01*
X354310Y-457869D01*
X353874Y-455536D01*
Y-453202D01*
X354310Y-450869D01*
X355184Y-448827D01*
X356494Y-447078D01*
X358022Y-445911D01*
X359769Y-445619D01*
X361515Y-445911D01*
X363044Y-447078D01*
X364354Y-448827D01*
X365228Y-450869D01*
X365664Y-453202D01*
Y-455536D01*
X365228Y-457869D01*
X364354Y-459911D01*
X363044Y-461661D01*
X361515Y-462827D01*
X359769Y-463119D01*
G01X410610Y-445619D02*
X416069Y-463119D01*
X421528Y-445619D01*
G01X437936Y-463119D02*
X429202D01*
Y-445619D01*
X437936D01*
G01X434442Y-454077D02*
X429202D01*
G01X446702Y-463119D02*
Y-445619D01*
X452161D01*
X453907Y-446494D01*
X454999Y-447661D01*
X455436Y-449994D01*
X454999Y-452328D01*
X453689Y-453786D01*
X452161Y-454661D01*
X446702D01*
G01X452161D02*
X455436Y-463119D01*
G01X468569Y-463702D02*
X468132Y-463411D01*
Y-462827D01*
X468569Y-462536D01*
X469006Y-462827D01*
Y-463411D01*
X468569Y-463702D01*
G01X433569Y-508119D02*
Y-490619D01*
X430949Y-494119D01*
G01Y-508119D02*
X436189D01*
G01X452815Y-498786D02*
X453689Y-497911D01*
X454344Y-496453D01*
X454781Y-494410D01*
X454344Y-492661D01*
X453471Y-491494D01*
X451942Y-490619D01*
X446047D01*
Y-508119D01*
X453252D01*
X454781Y-506953D01*
X455654Y-505202D01*
X456091Y-503161D01*
X455654Y-501119D01*
X454344Y-499369D01*
X452815Y-498786D01*
X446047D01*
G01X544152Y-490619D02*
Y-508119D01*
X552886D01*
G01X568639D02*
Y-490619D01*
X560560Y-503161D01*
X571478D01*
G01X578060Y-490619D02*
X583519Y-508119D01*
X588978Y-490619D01*
G01X605822Y-492078D02*
X604512Y-491202D01*
X602984Y-490619D01*
X601237D01*
X599272Y-491494D01*
X597744Y-492952D01*
X596652Y-494703D01*
X595779Y-497619D01*
X595560Y-500244D01*
X595997Y-502869D01*
X596652Y-504619D01*
X597962Y-506369D01*
X599491Y-507536D01*
X601019Y-508119D01*
X602547D01*
X604076Y-507536D01*
X605386Y-506661D01*
X606478Y-505495D01*
G01X623322Y-492078D02*
X622012Y-491202D01*
X620484Y-490619D01*
X618737D01*
X616772Y-491494D01*
X615244Y-492952D01*
X614152Y-494703D01*
X613279Y-497619D01*
X613060Y-500244D01*
X613497Y-502869D01*
X614152Y-504619D01*
X615462Y-506369D01*
X616991Y-507536D01*
X618519Y-508119D01*
X620047D01*
X621576Y-507536D01*
X622886Y-506661D01*
X623978Y-505495D01*
G01X544152Y-445619D02*
Y-463119D01*
X552886D01*
G01X569949D02*
Y-451453D01*
G01Y-453494D02*
X569076Y-452328D01*
X567765Y-451744D01*
X566237Y-451453D01*
X564709Y-452036D01*
X563399Y-453202D01*
X562525Y-454952D01*
X562089Y-457286D01*
X562525Y-459619D01*
X563399Y-461369D01*
X564709Y-462536D01*
X566237Y-463119D01*
X567765Y-462827D01*
X569076Y-461953D01*
X569949Y-460786D01*
G01X578934Y-468369D02*
X580244Y-468952D01*
X581991Y-468369D01*
X583082Y-467203D01*
X583956Y-465744D01*
X585265Y-461078D01*
X588104Y-451453D01*
G01X581117D02*
X585265Y-461078D01*
G01X597744Y-455244D02*
X604731D01*
X604076Y-453202D01*
X602984Y-452036D01*
X601456Y-451453D01*
X599927Y-451744D01*
X598617Y-452619D01*
X597744Y-454661D01*
X597307Y-456411D01*
Y-458161D01*
X597744Y-459911D01*
X598836Y-461661D01*
X600146Y-462827D01*
X601674Y-463119D01*
X603202Y-462536D01*
X604731Y-460786D01*
G01X615462Y-463119D02*
Y-451453D01*
G01Y-453786D02*
X616554Y-452619D01*
X617646Y-451744D01*
X619174Y-451453D01*
X620265Y-451744D01*
X621576Y-452619D01*
G01X686702Y-490619D02*
Y-508119D01*
X695436D01*
G01X703984Y-513369D02*
X705294Y-513952D01*
X707041Y-513369D01*
X708132Y-512203D01*
X709006Y-510744D01*
X710315Y-506078D01*
X713154Y-496453D01*
G01X706167D02*
X710315Y-506078D01*
G01X722357Y-508119D02*
Y-496453D01*
G01Y-499369D02*
X723231Y-497911D01*
X724541Y-496744D01*
X726287Y-496453D01*
X727815Y-496744D01*
X729126Y-497911D01*
X729781Y-499952D01*
Y-508119D01*
G01X739857D02*
Y-496453D01*
G01Y-499369D02*
X740731Y-497911D01*
X742041Y-496744D01*
X743787Y-496453D01*
X745315Y-496744D01*
X746626Y-497911D01*
X747281Y-499952D01*
Y-508119D01*
G01X774202Y-490619D02*
Y-508119D01*
X782936D01*
G01X796069Y-496453D02*
Y-508119D01*
G01Y-491786D02*
X795632Y-491494D01*
Y-490911D01*
X796069Y-490619D01*
X796506Y-490911D01*
Y-491494D01*
X796069Y-491786D01*
G01X809857Y-496453D02*
Y-504619D01*
X810731Y-506661D01*
X812041Y-507827D01*
X813569Y-508119D01*
X815097Y-507827D01*
X816407Y-506661D01*
X817281Y-504619D01*
G01Y-508119D02*
Y-496453D01*
G01X686266Y-463119D02*
Y-445619D01*
X690632D01*
X692379Y-446494D01*
X693689Y-447661D01*
X694781Y-449410D01*
X695654Y-451453D01*
X695872Y-454369D01*
X695654Y-457286D01*
X694781Y-459328D01*
X693689Y-461078D01*
X692379Y-462244D01*
X690632Y-463119D01*
X686266D01*
G01X705294Y-455244D02*
X712281D01*
X711626Y-453202D01*
X710534Y-452036D01*
X709006Y-451453D01*
X707477Y-451744D01*
X706167Y-452619D01*
X705294Y-454661D01*
X704857Y-456411D01*
Y-458161D01*
X705294Y-459911D01*
X706386Y-461661D01*
X707696Y-462827D01*
X709224Y-463119D01*
X710752Y-462536D01*
X712281Y-460786D01*
G01X722794Y-461078D02*
X723886Y-462244D01*
X725414Y-463119D01*
X726724D01*
X728034Y-462536D01*
X728907Y-461661D01*
X729344Y-460495D01*
X729126Y-458744D01*
X728252Y-457869D01*
X724322Y-456119D01*
X723449Y-454077D01*
X723886Y-452619D01*
X724759Y-451744D01*
X726069Y-451453D01*
X727379Y-451744D01*
X728689Y-452619D01*
G01X743569Y-451453D02*
Y-463119D01*
G01Y-446786D02*
X743132Y-446494D01*
Y-445911D01*
X743569Y-445619D01*
X744006Y-445911D01*
Y-446494D01*
X743569Y-446786D01*
G01X758012Y-467494D02*
X759541Y-468661D01*
X761287Y-468952D01*
X762815Y-468661D01*
X764126Y-467203D01*
X764999Y-465161D01*
Y-451453D01*
G01Y-453786D02*
X764126Y-452619D01*
X762815Y-451744D01*
X761287Y-451453D01*
X759541Y-452036D01*
X758449Y-453202D01*
X757575Y-455244D01*
X757139Y-457286D01*
X757357Y-459036D01*
X758231Y-461078D01*
X759541Y-462536D01*
X761287Y-463119D01*
X762597Y-462827D01*
X764126Y-461661D01*
X764999Y-460495D01*
G01X774857Y-463119D02*
Y-451453D01*
G01Y-454369D02*
X775731Y-452911D01*
X777041Y-451744D01*
X778787Y-451453D01*
X780315Y-451744D01*
X781626Y-452911D01*
X782281Y-454952D01*
Y-463119D01*
G01X792794Y-455244D02*
X799781D01*
X799126Y-453202D01*
X798034Y-452036D01*
X796506Y-451453D01*
X794977Y-451744D01*
X793667Y-452619D01*
X792794Y-454661D01*
X792357Y-456411D01*
Y-458161D01*
X792794Y-459911D01*
X793886Y-461661D01*
X795196Y-462827D01*
X796724Y-463119D01*
X798252Y-462536D01*
X799781Y-460786D01*
G01X810512Y-463119D02*
Y-451453D01*
G01Y-453786D02*
X811604Y-452619D01*
X812696Y-451744D01*
X814224Y-451453D01*
X815315Y-451744D01*
X816626Y-452619D01*
G01X857269Y-508119D02*
Y-490619D01*
X854649Y-494119D01*
G01Y-508119D02*
X859889D01*
G01X874769D02*
Y-490619D01*
X872149Y-494119D01*
G01Y-508119D02*
X877389D01*
G01X888339Y-508702D02*
X896199Y-490619D01*
G01X909769Y-508119D02*
Y-490619D01*
X907149Y-494119D01*
G01Y-508119D02*
X912389D01*
G01X922466Y-504619D02*
X923775Y-506661D01*
X925522Y-507827D01*
X927487Y-508119D01*
X929234Y-507827D01*
X930981Y-506369D01*
X932072Y-504619D01*
X932291Y-502869D01*
X931854Y-500828D01*
X930326Y-499369D01*
X928797Y-498786D01*
X926832D01*
G01X928797D02*
X930107Y-497911D01*
X931199Y-496453D01*
X931636Y-494703D01*
X931199Y-492952D01*
X930107Y-491494D01*
X928142Y-490619D01*
X926177Y-490911D01*
X924212Y-492078D01*
G01X940839Y-508702D02*
X948699Y-490619D01*
G01X958121Y-493536D02*
X959431Y-491786D01*
X960959Y-490911D01*
X962706Y-490619D01*
X964889Y-491202D01*
X966417Y-492661D01*
X966854Y-494410D01*
X966636Y-496161D01*
X965762Y-497619D01*
X961396Y-500536D01*
X959431Y-502577D01*
X958121Y-505495D01*
X957684Y-508119D01*
X966854D01*
G01X979769Y-490619D02*
X978022Y-491202D01*
X976712Y-492661D01*
X975839Y-494410D01*
X975184Y-496744D01*
X974966Y-499369D01*
X975184Y-501994D01*
X975839Y-504328D01*
X976712Y-506078D01*
X978022Y-507536D01*
X979769Y-508119D01*
X981515Y-507536D01*
X982826Y-506078D01*
X983699Y-504328D01*
X984354Y-501994D01*
X984572Y-499369D01*
X984354Y-496744D01*
X983699Y-494410D01*
X982826Y-492661D01*
X981515Y-491202D01*
X979769Y-490619D01*
G01X997269Y-508119D02*
Y-490619D01*
X994649Y-494119D01*
G01Y-508119D02*
X999889D01*
G01X1017389D02*
Y-490619D01*
X1009310Y-503161D01*
X1020228D01*
G01X904966Y-463119D02*
Y-445619D01*
X909332D01*
X911079Y-446494D01*
X912389Y-447661D01*
X913481Y-449410D01*
X914354Y-451453D01*
X914572Y-454369D01*
X914354Y-457286D01*
X913481Y-459328D01*
X912389Y-461078D01*
X911079Y-462244D01*
X909332Y-463119D01*
X904966D01*
G01X931199D02*
Y-451453D01*
G01Y-453494D02*
X930326Y-452328D01*
X929015Y-451744D01*
X927487Y-451453D01*
X925959Y-452036D01*
X924649Y-453202D01*
X923775Y-454952D01*
X923339Y-457286D01*
X923775Y-459619D01*
X924649Y-461369D01*
X925959Y-462536D01*
X927487Y-463119D01*
X929015Y-462827D01*
X930326Y-461953D01*
X931199Y-460786D01*
G01X944769Y-445619D02*
Y-463119D01*
G01X941712Y-451453D02*
X947826D01*
G01X958994Y-455244D02*
X965981D01*
X965326Y-453202D01*
X964234Y-452036D01*
X962706Y-451453D01*
X961177Y-451744D01*
X959867Y-452619D01*
X958994Y-454661D01*
X958557Y-456411D01*
Y-458161D01*
X958994Y-459911D01*
X960086Y-461661D01*
X961396Y-462827D01*
X962924Y-463119D01*
X964452Y-462536D01*
X965981Y-460786D01*
M02*
